(kicad_sch
	(version 20250114)
	(generator "eeschema")
	(generator_version "9.0")
	(paper "A3")
	(title_block
		(title "CM4 Baseboard")
		(date "2026-01-05")
		(rev "1.1.1")
		(company "Antmicro Ltd")
		(comment 1 "www.antmicro.com")
	)
	(bus_alias "NFC"
		(members "EN" "IRQ" "DWL_REQ" "WKUP_REQ")
	)
	(text "GPIO protection"
		(exclude_from_sim no)
		(at 109.22 153.67 0)
		(effects
			(font
				(size 2.9972 2.9972)
				(thickness 0.5994)
				(bold yes)
			)
			(justify left bottom)
		)
	)
	(text "External antenna"
		(exclude_from_sim no)
		(at 375.92 82.55 0)
		(effects
			(font
				(size 1.27 1.27)
			)
			(justify left bottom)
		)
	)
	(text "Note:\nI_{2}C address selection\nADR1 	| ADR0 	| Write address\n0 		| 0		| 0x50\n0 		| 1 	| 0x52\n1 		| 0 	| 0x54\n1 		| 1 	| 0x56"
		(exclude_from_sim no)
		(at 223.52 154.94 0)
		(effects
			(font
				(size 1.27 1.27)
			)
			(justify left bottom)
		)
	)
	(text "Note:\nMatching network components values has \nto be selected for specific antenna"
		(exclude_from_sim no)
		(at 316.23 85.09 0)
		(effects
			(font
				(size 1.27 1.27)
			)
			(justify left bottom)
		)
	)
	(text "GPIO connector"
		(exclude_from_sim no)
		(at 19.05 153.67 0)
		(effects
			(font
				(size 2.9972 2.9972)
				(thickness 0.5994)
				(bold yes)
			)
			(justify left bottom)
		)
	)
	(text "Note:\nFollows RPi connector pinout, \nexcept pins 14 & 30 (analog input)"
		(exclude_from_sim no)
		(at 21.59 163.83 0)
		(effects
			(font
				(size 1.27 1.27)
			)
			(justify left bottom)
		)
	)
	(text "NFC Module"
		(exclude_from_sim no)
		(at 223.266 34.036 0)
		(effects
			(font
				(size 2.9972 2.9972)
				(thickness 0.5994)
				(bold yes)
			)
			(justify left bottom)
		)
	)
	(text "QWIIC LED strip connector"
		(exclude_from_sim no)
		(at 60.96 80.01 0)
		(effects
			(font
				(size 2.54 2.54)
				(thickness 0.508)
				(bold yes)
			)
			(justify left bottom)
		)
	)
	(text "QWIIC sensor connector"
		(exclude_from_sim no)
		(at 60.96 27.94 0)
		(effects
			(font
				(size 2.54 2.54)
				(thickness 0.508)
				(bold yes)
			)
			(justify left bottom)
		)
	)
	(text "NFC"
		(exclude_from_sim no)
		(at 381 96.52 0)
		(effects
			(font
				(size 3 3)
				(thickness 0.6)
				(bold yes)
			)
			(justify left bottom)
		)
	)
	(text "RTC"
		(exclude_from_sim no)
		(at 223.266 190.754 0)
		(effects
			(font
				(size 2.9972 2.9972)
				(thickness 0.5994)
				(bold yes)
			)
			(justify left bottom)
		)
	)
	(junction
		(at 248.92 55.88)
		(diameter 0)
		(color 0 0 0 0)
	)
	(junction
		(at 236.22 123.19)
		(diameter 0)
		(color 0 0 0 0)
	)
	(junction
		(at 331.47 123.19)
		(diameter 0)
		(color 0 0 0 0)
	)
	(junction
		(at 257.81 55.88)
		(diameter 0)
		(color 0 0 0 0)
	)
	(junction
		(at 43.18 227.33)
		(diameter 0)
		(color 0 0 0 0)
	)
	(junction
		(at 96.52 100.33)
		(diameter 0)
		(color 0 0 0 0)
	)
	(junction
		(at 58.42 179.07)
		(diameter 0)
		(color 0 0 0 0)
	)
	(junction
		(at 152.4 111.76)
		(diameter 0)
		(color 0 0 0 0)
	)
	(junction
		(at 322.58 123.19)
		(diameter 0)
		(color 0 0 0 0)
	)
	(junction
		(at 275.59 140.97)
		(diameter 0)
		(color 0 0 0 0)
	)
	(junction
		(at 248.92 68.58)
		(diameter 0)
		(color 0 0 0 0)
	)
	(junction
		(at 360.68 107.95)
		(diameter 0)
		(color 0 0 0 0)
	)
	(junction
		(at 41.91 179.07)
		(diameter 0)
		(color 0 0 0 0)
	)
	(junction
		(at 350.52 115.57)
		(diameter 0)
		(color 0 0 0 0)
	)
	(junction
		(at 248.92 81.28)
		(diameter 0)
		(color 0 0 0 0)
	)
	(junction
		(at 309.88 158.75)
		(diameter 0)
		(color 0 0 0 0)
	)
	(junction
		(at 320.04 158.75)
		(diameter 0)
		(color 0 0 0 0)
	)
	(junction
		(at 314.96 166.37)
		(diameter 0)
		(color 0 0 0 0)
	)
	(junction
		(at 331.47 107.95)
		(diameter 0)
		(color 0 0 0 0)
	)
	(junction
		(at 257.81 68.58)
		(diameter 0)
		(color 0 0 0 0)
	)
	(junction
		(at 345.44 123.19)
		(diameter 0)
		(color 0 0 0 0)
	)
	(junction
		(at 76.2 168.91)
		(diameter 0)
		(color 0 0 0 0)
	)
	(junction
		(at 275.59 143.51)
		(diameter 0)
		(color 0 0 0 0)
	)
	(junction
		(at 106.68 113.03)
		(diameter 0)
		(color 0 0 0 0)
	)
	(junction
		(at 257.81 81.28)
		(diameter 0)
		(color 0 0 0 0)
	)
	(junction
		(at 43.18 209.55)
		(diameter 0)
		(color 0 0 0 0)
	)
	(junction
		(at 322.58 115.57)
		(diameter 0)
		(color 0 0 0 0)
	)
	(junction
		(at 264.16 140.97)
		(diameter 0)
		(color 0 0 0 0)
	)
	(junction
		(at 331.47 115.57)
		(diameter 0)
		(color 0 0 0 0)
	)
	(junction
		(at 264.16 146.05)
		(diameter 0)
		(color 0 0 0 0)
	)
	(junction
		(at 248.92 210.82)
		(diameter 0)
		(color 0 0 0 0)
	)
	(junction
		(at 300.99 220.98)
		(diameter 0)
		(color 0 0 0 0)
	)
	(junction
		(at 275.59 137.16)
		(diameter 0)
		(color 0 0 0 0)
	)
	(junction
		(at 360.68 115.57)
		(diameter 0)
		(color 0 0 0 0)
	)
	(junction
		(at 58.42 219.71)
		(diameter 0)
		(color 0 0 0 0)
	)
	(junction
		(at 337.82 123.19)
		(diameter 0)
		(color 0 0 0 0)
	)
	(junction
		(at 350.52 107.95)
		(diameter 0)
		(color 0 0 0 0)
	)
	(junction
		(at 350.52 123.19)
		(diameter 0)
		(color 0 0 0 0)
	)
	(junction
		(at 275.59 146.05)
		(diameter 0)
		(color 0 0 0 0)
	)
	(junction
		(at 275.59 134.62)
		(diameter 0)
		(color 0 0 0 0)
	)
	(junction
		(at 243.84 125.73)
		(diameter 0)
		(color 0 0 0 0)
	)
	(junction
		(at 275.59 132.08)
		(diameter 0)
		(color 0 0 0 0)
	)
	(junction
		(at 322.58 107.95)
		(diameter 0)
		(color 0 0 0 0)
	)
	(junction
		(at 58.42 201.93)
		(diameter 0)
		(color 0 0 0 0)
	)
	(junction
		(at 264.16 149.86)
		(diameter 0)
		(color 0 0 0 0)
	)
	(junction
		(at 106.68 50.8)
		(diameter 0)
		(color 0 0 0 0)
	)
	(junction
		(at 151.13 49.53)
		(diameter 0)
		(color 0 0 0 0)
	)
	(junction
		(at 360.68 123.19)
		(diameter 0)
		(color 0 0 0 0)
	)
	(junction
		(at 337.82 107.95)
		(diameter 0)
		(color 0 0 0 0)
	)
	(junction
		(at 345.44 107.95)
		(diameter 0)
		(color 0 0 0 0)
	)
	(junction
		(at 264.16 137.16)
		(diameter 0)
		(color 0 0 0 0)
	)
	(no_connect
		(at 278.13 223.52)
	)
	(bus_entry
		(at 24.13 189.23)
		(size 2.54 2.54)
		(stroke
			(width 0)
			(type default)
		)
	)
	(bus_entry
		(at 163.83 226.06)
		(size 2.54 2.54)
		(stroke
			(width 0)
			(type default)
		)
	)
	(bus_entry
		(at 111.76 168.91)
		(size 2.54 2.54)
		(stroke
			(width 0)
			(type default)
		)
	)
	(bus_entry
		(at 24.13 184.15)
		(size 2.54 2.54)
		(stroke
			(width 0)
			(type default)
		)
	)
	(bus_entry
		(at 83.82 40.64)
		(size 2.54 2.54)
		(stroke
			(width 0)
			(type default)
		)
	)
	(bus_entry
		(at 111.76 227.33)
		(size 2.54 2.54)
		(stroke
			(width 0)
			(type default)
		)
	)
	(bus_entry
		(at 76.2 196.85)
		(size -2.54 2.54)
		(stroke
			(width 0)
			(type default)
		)
	)
	(bus_entry
		(at 163.83 170.18)
		(size 2.54 2.54)
		(stroke
			(width 0)
			(type default)
		)
	)
	(bus_entry
		(at 163.83 172.72)
		(size 2.54 2.54)
		(stroke
			(width 0)
			(type default)
		)
	)
	(bus_entry
		(at 24.13 181.61)
		(size 2.54 2.54)
		(stroke
			(width 0)
			(type default)
		)
	)
	(bus_entry
		(at 24.13 217.17)
		(size 2.54 2.54)
		(stroke
			(width 0)
			(type default)
		)
	)
	(bus_entry
		(at 111.76 224.79)
		(size 2.54 2.54)
		(stroke
			(width 0)
			(type default)
		)
	)
	(bus_entry
		(at 111.76 171.45)
		(size 2.54 2.54)
		(stroke
			(width 0)
			(type default)
		)
	)
	(bus_entry
		(at 111.76 205.74)
		(size 2.54 2.54)
		(stroke
			(width 0)
			(type default)
		)
	)
	(bus_entry
		(at 267.97 120.65)
		(size -1.27 -1.27)
		(stroke
			(width 0)
			(type default)
		)
	)
	(bus_entry
		(at 24.13 209.55)
		(size 2.54 2.54)
		(stroke
			(width 0)
			(type default)
		)
	)
	(bus_entry
		(at 163.83 231.14)
		(size 2.54 2.54)
		(stroke
			(width 0)
			(type default)
		)
	)
	(bus_entry
		(at 76.2 224.79)
		(size -2.54 2.54)
		(stroke
			(width 0)
			(type default)
		)
	)
	(bus_entry
		(at 83.82 43.18)
		(size 2.54 2.54)
		(stroke
			(width 0)
			(type default)
		)
	)
	(bus_entry
		(at 83.82 105.41)
		(size 2.54 2.54)
		(stroke
			(width 0)
			(type default)
		)
	)
	(bus_entry
		(at 163.83 189.23)
		(size 2.54 2.54)
		(stroke
			(width 0)
			(type default)
		)
	)
	(bus_entry
		(at 111.76 229.87)
		(size 2.54 2.54)
		(stroke
			(width 0)
			(type default)
		)
	)
	(bus_entry
		(at 163.83 207.01)
		(size 2.54 2.54)
		(stroke
			(width 0)
			(type default)
		)
	)
	(bus_entry
		(at 111.76 185.42)
		(size 2.54 2.54)
		(stroke
			(width 0)
			(type default)
		)
	)
	(bus_entry
		(at 165.1 101.6)
		(size -2.54 2.54)
		(stroke
			(width 0)
			(type default)
		)
	)
	(bus_entry
		(at 24.13 222.25)
		(size 2.54 2.54)
		(stroke
			(width 0)
			(type default)
		)
	)
	(bus_entry
		(at 83.82 43.18)
		(size 2.54 2.54)
		(stroke
			(width 0)
			(type default)
		)
	)
	(bus_entry
		(at 111.76 187.96)
		(size 2.54 2.54)
		(stroke
			(width 0)
			(type default)
		)
	)
	(bus_entry
		(at 76.2 212.09)
		(size -2.54 2.54)
		(stroke
			(width 0)
			(type default)
		)
	)
	(bus_entry
		(at 76.2 194.31)
		(size -2.54 2.54)
		(stroke
			(width 0)
			(type default)
		)
	)
	(bus_entry
		(at 111.76 210.82)
		(size 2.54 2.54)
		(stroke
			(width 0)
			(type default)
		)
	)
	(bus_entry
		(at 111.76 208.28)
		(size 2.54 2.54)
		(stroke
			(width 0)
			(type default)
		)
	)
	(bus_entry
		(at 76.2 201.93)
		(size -2.54 2.54)
		(stroke
			(width 0)
			(type default)
		)
	)
	(bus_entry
		(at 24.13 191.77)
		(size 2.54 2.54)
		(stroke
			(width 0)
			(type default)
		)
	)
	(bus_entry
		(at 83.82 40.64)
		(size 2.54 2.54)
		(stroke
			(width 0)
			(type default)
		)
	)
	(bus_entry
		(at 76.2 219.71)
		(size -2.54 2.54)
		(stroke
			(width 0)
			(type default)
		)
	)
	(bus_entry
		(at 163.83 223.52)
		(size 2.54 2.54)
		(stroke
			(width 0)
			(type default)
		)
	)
	(bus_entry
		(at 111.76 190.5)
		(size 2.54 2.54)
		(stroke
			(width 0)
			(type default)
		)
	)
	(bus_entry
		(at 83.82 105.41)
		(size 2.54 2.54)
		(stroke
			(width 0)
			(type default)
		)
	)
	(bus_entry
		(at 83.82 102.87)
		(size 2.54 2.54)
		(stroke
			(width 0)
			(type default)
		)
	)
	(bus_entry
		(at 165.1 99.06)
		(size -2.54 2.54)
		(stroke
			(width 0)
			(type default)
		)
	)
	(bus_entry
		(at 76.2 207.01)
		(size -2.54 2.54)
		(stroke
			(width 0)
			(type default)
		)
	)
	(bus_entry
		(at 165.1 99.06)
		(size -2.54 2.54)
		(stroke
			(width 0)
			(type default)
		)
	)
	(bus_entry
		(at 163.83 209.55)
		(size 2.54 2.54)
		(stroke
			(width 0)
			(type default)
		)
	)
	(bus_entry
		(at 163.83 228.6)
		(size 2.54 2.54)
		(stroke
			(width 0)
			(type default)
		)
	)
	(bus_entry
		(at 24.13 212.09)
		(size 2.54 2.54)
		(stroke
			(width 0)
			(type default)
		)
	)
	(bus_entry
		(at 163.83 186.69)
		(size 2.54 2.54)
		(stroke
			(width 0)
			(type default)
		)
	)
	(bus_entry
		(at 165.1 101.6)
		(size -2.54 2.54)
		(stroke
			(width 0)
			(type default)
		)
	)
	(bus_entry
		(at 163.83 39.37)
		(size -2.54 2.54)
		(stroke
			(width 0)
			(type default)
		)
	)
	(bus_entry
		(at 256.54 111.76)
		(size -1.27 -1.27)
		(stroke
			(width 0)
			(type default)
		)
	)
	(bus_entry
		(at 256.54 128.27)
		(size -1.27 -1.27)
		(stroke
			(width 0)
			(type default)
		)
	)
	(bus_entry
		(at 163.83 212.09)
		(size 2.54 2.54)
		(stroke
			(width 0)
			(type default)
		)
	)
	(bus_entry
		(at 76.2 204.47)
		(size -2.54 2.54)
		(stroke
			(width 0)
			(type default)
		)
	)
	(bus_entry
		(at 76.2 214.63)
		(size -2.54 2.54)
		(stroke
			(width 0)
			(type default)
		)
	)
	(bus_entry
		(at 76.2 191.77)
		(size -2.54 2.54)
		(stroke
			(width 0)
			(type default)
		)
	)
	(bus_entry
		(at 76.2 222.25)
		(size -2.54 2.54)
		(stroke
			(width 0)
			(type default)
		)
	)
	(bus_entry
		(at 163.83 167.64)
		(size 2.54 2.54)
		(stroke
			(width 0)
			(type default)
		)
	)
	(bus_entry
		(at 24.13 179.07)
		(size 2.54 2.54)
		(stroke
			(width 0)
			(type default)
		)
	)
	(bus_entry
		(at 163.83 39.37)
		(size -2.54 2.54)
		(stroke
			(width 0)
			(type default)
		)
	)
	(bus_entry
		(at 76.2 209.55)
		(size -2.54 2.54)
		(stroke
			(width 0)
			(type default)
		)
	)
	(bus_entry
		(at 111.76 166.37)
		(size 2.54 2.54)
		(stroke
			(width 0)
			(type default)
		)
	)
	(bus_entry
		(at 24.13 204.47)
		(size 2.54 2.54)
		(stroke
			(width 0)
			(type default)
		)
	)
	(bus_entry
		(at 256.54 101.6)
		(size -1.27 -1.27)
		(stroke
			(width 0)
			(type default)
		)
	)
	(bus_entry
		(at 24.13 219.71)
		(size 2.54 2.54)
		(stroke
			(width 0)
			(type default)
		)
	)
	(bus_entry
		(at 256.54 106.68)
		(size -1.27 -1.27)
		(stroke
			(width 0)
			(type default)
		)
	)
	(bus_entry
		(at 111.76 182.88)
		(size 2.54 2.54)
		(stroke
			(width 0)
			(type default)
		)
	)
	(bus_entry
		(at 163.83 36.83)
		(size -2.54 2.54)
		(stroke
			(width 0)
			(type default)
		)
	)
	(bus_entry
		(at 76.2 184.15)
		(size -2.54 2.54)
		(stroke
			(width 0)
			(type default)
		)
	)
	(bus_entry
		(at 163.83 184.15)
		(size 2.54 2.54)
		(stroke
			(width 0)
			(type default)
		)
	)
	(bus_entry
		(at 76.2 189.23)
		(size -2.54 2.54)
		(stroke
			(width 0)
			(type default)
		)
	)
	(bus_entry
		(at 111.76 222.25)
		(size 2.54 2.54)
		(stroke
			(width 0)
			(type default)
		)
	)
	(bus_entry
		(at 163.83 191.77)
		(size 2.54 2.54)
		(stroke
			(width 0)
			(type default)
		)
	)
	(bus_entry
		(at 76.2 186.69)
		(size -2.54 2.54)
		(stroke
			(width 0)
			(type default)
		)
	)
	(bus_entry
		(at 163.83 204.47)
		(size 2.54 2.54)
		(stroke
			(width 0)
			(type default)
		)
	)
	(bus_entry
		(at 83.82 102.87)
		(size 2.54 2.54)
		(stroke
			(width 0)
			(type default)
		)
	)
	(bus_entry
		(at 24.13 201.93)
		(size 2.54 2.54)
		(stroke
			(width 0)
			(type default)
		)
	)
	(bus_entry
		(at 163.83 36.83)
		(size -2.54 2.54)
		(stroke
			(width 0)
			(type default)
		)
	)
	(bus_entry
		(at 24.13 214.63)
		(size 2.54 2.54)
		(stroke
			(width 0)
			(type default)
		)
	)
	(bus_entry
		(at 111.76 203.2)
		(size 2.54 2.54)
		(stroke
			(width 0)
			(type default)
		)
	)
	(bus_entry
		(at 24.13 194.31)
		(size 2.54 2.54)
		(stroke
			(width 0)
			(type default)
		)
	)
	(bus_entry
		(at 267.97 118.11)
		(size -1.27 -1.27)
		(stroke
			(width 0)
			(type default)
		)
	)
	(bus_entry
		(at 24.13 199.39)
		(size 2.54 2.54)
		(stroke
			(width 0)
			(type default)
		)
	)
	(wire
		(pts
			(xy 331.47 100.33) (xy 331.47 101.6)
		)
		(stroke
			(width 0)
			(type default)
		)
	)
	(bus
		(pts
			(xy 111.76 166.37) (xy 111.76 168.91)
		)
		(stroke
			(width 0)
			(type default)
		)
	)
	(bus
		(pts
			(xy 24.13 214.63) (xy 24.13 217.17)
		)
		(stroke
			(width 0)
			(type default)
		)
	)
	(polyline
		(pts
			(xy 20.32 165.1) (xy 57.15 165.1)
		)
		(stroke
			(width 0)
			(type default)
		)
	)
	(wire
		(pts
			(xy 337.82 100.33) (xy 339.09 100.33)
		)
		(stroke
			(width 0)
			(type default)
		)
	)
	(wire
		(pts
			(xy 132.08 185.42) (xy 114.3 185.42)
		)
		(stroke
			(width 0)
			(type default)
		)
	)
	(wire
		(pts
			(xy 300.99 219.71) (xy 300.99 220.98)
		)
		(stroke
			(width 0)
			(type default)
		)
	)
	(polyline
		(pts
			(xy 379.73 86.36) (xy 392.43 86.36)
		)
		(stroke
			(width 0.3)
			(type solid)
		)
	)
	(wire
		(pts
			(xy 132.08 208.28) (xy 114.3 208.28)
		)
		(stroke
			(width 0)
			(type default)
		)
	)
	(bus
		(pts
			(xy 163.83 166.37) (xy 163.83 167.64)
		)
		(stroke
			(width 0)
			(type default)
		)
	)
	(polyline
		(pts
			(xy 222.25 156.21) (xy 259.08 156.21)
		)
		(stroke
			(width 0)
			(type default)
		)
	)
	(wire
		(pts
			(xy 275.59 146.05) (xy 273.05 146.05)
		)
		(stroke
			(width 0)
			(type default)
		)
	)
	(wire
		(pts
			(xy 166.37 172.72) (xy 182.88 172.72)
		)
		(stroke
			(width 0)
			(type default)
		)
	)
	(wire
		(pts
			(xy 360.68 115.57) (xy 360.68 116.84)
		)
		(stroke
			(width 0)
			(type default)
		)
	)
	(bus
		(pts
			(xy 76.2 207.01) (xy 76.2 209.55)
		)
		(stroke
			(width 0)
			(type default)
		)
	)
	(wire
		(pts
			(xy 243.84 114.3) (xy 243.84 115.57)
		)
		(stroke
			(width 0)
			(type default)
		)
	)
	(wire
		(pts
			(xy 309.88 165.1) (xy 309.88 166.37)
		)
		(stroke
			(width 0)
			(type default)
		)
	)
	(wire
		(pts
			(xy 256.54 210.82) (xy 256.54 220.98)
		)
		(stroke
			(width 0)
			(type default)
		)
	)
	(wire
		(pts
			(xy 372.11 114.3) (xy 375.92 114.3)
		)
		(stroke
			(width 0)
			(type default)
		)
	)
	(wire
		(pts
			(xy 300.99 227.33) (xy 300.99 228.6)
		)
		(stroke
			(width 0)
			(type default)
		)
	)
	(wire
		(pts
			(xy 320.04 165.1) (xy 320.04 166.37)
		)
		(stroke
			(width 0)
			(type default)
		)
	)
	(wire
		(pts
			(xy 275.59 134.62) (xy 275.59 132.08)
		)
		(stroke
			(width 0)
			(type default)
		)
	)
	(bus
		(pts
			(xy 266.7 116.84) (xy 266.7 119.38)
		)
		(stroke
			(width 0)
			(type default)
		)
	)
	(wire
		(pts
			(xy 55.88 199.39) (xy 73.66 199.39)
		)
		(stroke
			(width 0)
			(type default)
		)
	)
	(bus
		(pts
			(xy 111.76 227.33) (xy 111.76 229.87)
		)
		(stroke
			(width 0)
			(type default)
		)
	)
	(wire
		(pts
			(xy 256.54 106.68) (xy 276.86 106.68)
		)
		(stroke
			(width 0)
			(type default)
		)
	)
	(wire
		(pts
			(xy 130.81 195.58) (xy 130.81 196.85)
		)
		(stroke
			(width 0)
			(type default)
		)
	)
	(wire
		(pts
			(xy 256.54 128.27) (xy 276.86 128.27)
		)
		(stroke
			(width 0)
			(type default)
		)
	)
	(wire
		(pts
			(xy 182.88 236.22) (xy 181.61 236.22)
		)
		(stroke
			(width 0)
			(type default)
		)
	)
	(wire
		(pts
			(xy 114.3 193.04) (xy 132.08 193.04)
		)
		(stroke
			(width 0)
			(type default)
		)
	)
	(bus
		(pts
			(xy 163.83 189.23) (xy 163.83 191.77)
		)
		(stroke
			(width 0)
			(type default)
		)
	)
	(wire
		(pts
			(xy 132.08 213.36) (xy 114.3 213.36)
		)
		(stroke
			(width 0)
			(type default)
		)
	)
	(bus
		(pts
			(xy 24.13 217.17) (xy 24.13 219.71)
		)
		(stroke
			(width 0)
			(type default)
		)
	)
	(wire
		(pts
			(xy 307.34 100.33) (xy 309.88 100.33)
		)
		(stroke
			(width 0)
			(type default)
		)
	)
	(wire
		(pts
			(xy 44.45 204.47) (xy 26.67 204.47)
		)
		(stroke
			(width 0)
			(type default)
		)
	)
	(wire
		(pts
			(xy 307.34 130.81) (xy 309.88 130.81)
		)
		(stroke
			(width 0)
			(type default)
		)
	)
	(polyline
		(pts
			(xy 393.7 101.6) (xy 379.73 101.6)
		)
		(stroke
			(width 0.3)
			(type solid)
		)
	)
	(wire
		(pts
			(xy 257.81 81.28) (xy 257.81 82.55)
		)
		(stroke
			(width 0)
			(type default)
		)
	)
	(wire
		(pts
			(xy 91.44 100.33) (xy 96.52 100.33)
		)
		(stroke
			(width 0)
			(type default)
		)
	)
	(wire
		(pts
			(xy 350.52 109.22) (xy 350.52 107.95)
		)
		(stroke
			(width 0)
			(type default)
		)
	)
	(wire
		(pts
			(xy 257.81 55.88) (xy 257.81 57.15)
		)
		(stroke
			(width 0)
			(type default)
		)
	)
	(wire
		(pts
			(xy 344.17 107.95) (xy 345.44 107.95)
		)
		(stroke
			(width 0)
			(type default)
		)
	)
	(wire
		(pts
			(xy 337.82 107.95) (xy 337.82 100.33)
		)
		(stroke
			(width 0)
			(type default)
		)
	)
	(wire
		(pts
			(xy 275.59 137.16) (xy 273.05 137.16)
		)
		(stroke
			(width 0)
			(type default)
		)
	)
	(bus
		(pts
			(xy 83.82 39.37) (xy 83.82 40.64)
		)
		(stroke
			(width 0)
			(type default)
		)
	)
	(wire
		(pts
			(xy 44.45 194.31) (xy 26.67 194.31)
		)
		(stroke
			(width 0)
			(type default)
		)
	)
	(wire
		(pts
			(xy 91.44 96.52) (xy 91.44 100.33)
		)
		(stroke
			(width 0)
			(type default)
		)
	)
	(wire
		(pts
			(xy 41.91 177.8) (xy 41.91 179.07)
		)
		(stroke
			(width 0)
			(type default)
		)
	)
	(wire
		(pts
			(xy 44.45 191.77) (xy 26.67 191.77)
		)
		(stroke
			(width 0)
			(type default)
		)
	)
	(wire
		(pts
			(xy 130.81 163.83) (xy 130.81 166.37)
		)
		(stroke
			(width 0)
			(type default)
		)
	)
	(bus
		(pts
			(xy 163.83 170.18) (xy 163.83 172.72)
		)
		(stroke
			(width 0)
			(type default)
		)
	)
	(wire
		(pts
			(xy 96.52 110.49) (xy 96.52 100.33)
		)
		(stroke
			(width 0)
			(type default)
		)
	)
	(wire
		(pts
			(xy 236.22 120.65) (xy 236.22 123.19)
		)
		(stroke
			(width 0)
			(type default)
		)
	)
	(wire
		(pts
			(xy 314.96 138.43) (xy 360.68 138.43)
		)
		(stroke
			(width 0)
			(type default)
		)
	)
	(wire
		(pts
			(xy 350.52 115.57) (xy 346.71 115.57)
		)
		(stroke
			(width 0)
			(type default)
		)
	)
	(wire
		(pts
			(xy 264.16 146.05) (xy 264.16 149.86)
		)
		(stroke
			(width 0)
			(type default)
		)
	)
	(wire
		(pts
			(xy 275.59 114.3) (xy 276.86 114.3)
		)
		(stroke
			(width 0)
			(type default)
		)
	)
	(wire
		(pts
			(xy 307.34 138.43) (xy 309.88 138.43)
		)
		(stroke
			(width 0)
			(type default)
		)
	)
	(polyline
		(pts
			(xy 20.32 157.48) (xy 20.32 165.1)
		)
		(stroke
			(width 0)
			(type default)
		)
	)
	(wire
		(pts
			(xy 275.59 134.62) (xy 275.59 137.16)
		)
		(stroke
			(width 0)
			(type default)
		)
	)
	(bus
		(pts
			(xy 24.13 199.39) (xy 24.13 201.93)
		)
		(stroke
			(width 0)
			(type default)
		)
	)
	(wire
		(pts
			(xy 267.97 120.65) (xy 276.86 120.65)
		)
		(stroke
			(width 0)
			(type default)
		)
	)
	(wire
		(pts
			(xy 43.18 227.33) (xy 44.45 227.33)
		)
		(stroke
			(width 0)
			(type default)
		)
	)
	(wire
		(pts
			(xy 132.08 210.82) (xy 114.3 210.82)
		)
		(stroke
			(width 0)
			(type default)
		)
	)
	(bus
		(pts
			(xy 255.27 105.41) (xy 255.27 110.49)
		)
		(stroke
			(width 0)
			(type default)
		)
	)
	(wire
		(pts
			(xy 248.92 82.55) (xy 248.92 81.28)
		)
		(stroke
			(width 0)
			(type default)
		)
	)
	(wire
		(pts
			(xy 86.36 105.41) (xy 109.22 105.41)
		)
		(stroke
			(width 0)
			(type default)
		)
	)
	(wire
		(pts
			(xy 182.88 228.6) (xy 166.37 228.6)
		)
		(stroke
			(width 0)
			(type default)
		)
	)
	(wire
		(pts
			(xy 320.04 151.13) (xy 320.04 158.75)
		)
		(stroke
			(width 0)
			(type default)
		)
	)
	(wire
		(pts
			(xy 106.68 50.8) (xy 106.68 53.34)
		)
		(stroke
			(width 0)
			(type default)
		)
	)
	(polyline
		(pts
			(xy 102.87 133.35) (xy 102.87 284.48)
		)
		(stroke
			(width 0)
			(type default)
		)
	)
	(wire
		(pts
			(xy 55.88 214.63) (xy 73.66 214.63)
		)
		(stroke
			(width 0)
			(type default)
		)
	)
	(wire
		(pts
			(xy 130.81 166.37) (xy 132.08 166.37)
		)
		(stroke
			(width 0)
			(type default)
		)
	)
	(wire
		(pts
			(xy 182.88 226.06) (xy 166.37 226.06)
		)
		(stroke
			(width 0)
			(type default)
		)
	)
	(wire
		(pts
			(xy 300.99 213.36) (xy 300.99 214.63)
		)
		(stroke
			(width 0)
			(type default)
		)
	)
	(wire
		(pts
			(xy 44.45 186.69) (xy 26.67 186.69)
		)
		(stroke
			(width 0)
			(type default)
		)
	)
	(bus
		(pts
			(xy 163.83 212.09) (xy 163.83 223.52)
		)
		(stroke
			(width 0)
			(type default)
		)
	)
	(wire
		(pts
			(xy 248.92 62.23) (xy 248.92 68.58)
		)
		(stroke
			(width 0)
			(type default)
		)
	)
	(wire
		(pts
			(xy 350.52 107.95) (xy 360.68 107.95)
		)
		(stroke
			(width 0)
			(type default)
		)
	)
	(bus
		(pts
			(xy 76.2 212.09) (xy 76.2 214.63)
		)
		(stroke
			(width 0)
			(type default)
		)
	)
	(wire
		(pts
			(xy 322.58 115.57) (xy 322.58 116.84)
		)
		(stroke
			(width 0)
			(type default)
		)
	)
	(bus
		(pts
			(xy 24.13 209.55) (xy 24.13 212.09)
		)
		(stroke
			(width 0)
			(type default)
		)
	)
	(wire
		(pts
			(xy 96.52 110.49) (xy 109.22 110.49)
		)
		(stroke
			(width 0)
			(type default)
		)
	)
	(wire
		(pts
			(xy 273.05 140.97) (xy 275.59 140.97)
		)
		(stroke
			(width 0)
			(type default)
		)
	)
	(wire
		(pts
			(xy 345.44 100.33) (xy 345.44 107.95)
		)
		(stroke
			(width 0)
			(type default)
		)
	)
	(wire
		(pts
			(xy 273.05 149.86) (xy 276.86 149.86)
		)
		(stroke
			(width 0)
			(type default)
		)
	)
	(wire
		(pts
			(xy 55.88 179.07) (xy 58.42 179.07)
		)
		(stroke
			(width 0)
			(type default)
		)
	)
	(polyline
		(pts
			(xy 12.7 71.12) (xy 210.82 71.12)
		)
		(stroke
			(width 0)
			(type default)
		)
	)
	(bus
		(pts
			(xy 83.82 40.64) (xy 83.82 43.18)
		)
		(stroke
			(width 0)
			(type default)
		)
	)
	(bus
		(pts
			(xy 24.13 181.61) (xy 24.13 184.15)
		)
		(stroke
			(width 0)
			(type default)
		)
	)
	(wire
		(pts
			(xy 314.96 166.37) (xy 320.04 166.37)
		)
		(stroke
			(width 0)
			(type default)
		)
	)
	(bus
		(pts
			(xy 163.83 172.72) (xy 163.83 184.15)
		)
		(stroke
			(width 0)
			(type default)
		)
	)
	(wire
		(pts
			(xy 278.13 220.98) (xy 300.99 220.98)
		)
		(stroke
			(width 0)
			(type default)
		)
	)
	(wire
		(pts
			(xy 182.88 214.63) (xy 166.37 214.63)
		)
		(stroke
			(width 0)
			(type default)
		)
	)
	(bus
		(pts
			(xy 255.27 110.49) (xy 255.27 127)
		)
		(stroke
			(width 0)
			(type default)
		)
	)
	(wire
		(pts
			(xy 58.42 184.15) (xy 58.42 201.93)
		)
		(stroke
			(width 0)
			(type default)
		)
	)
	(wire
		(pts
			(xy 240.03 68.58) (xy 248.92 68.58)
		)
		(stroke
			(width 0)
			(type default)
		)
	)
	(wire
		(pts
			(xy 275.59 104.14) (xy 276.86 104.14)
		)
		(stroke
			(width 0)
			(type default)
		)
	)
	(wire
		(pts
			(xy 58.42 201.93) (xy 58.42 219.71)
		)
		(stroke
			(width 0)
			(type default)
		)
	)
	(wire
		(pts
			(xy 182.88 231.14) (xy 166.37 231.14)
		)
		(stroke
			(width 0)
			(type default)
		)
	)
	(polyline
		(pts
			(xy 377.19 83.82) (xy 394.97 83.82)
		)
		(stroke
			(width 0.3)
			(type solid)
		)
	)
	(wire
		(pts
			(xy 275.59 143.51) (xy 275.59 146.05)
		)
		(stroke
			(width 0)
			(type default)
		)
	)
	(polyline
		(pts
			(xy 394.97 83.82) (xy 394.97 102.87)
		)
		(stroke
			(width 0.3)
			(type solid)
		)
	)
	(wire
		(pts
			(xy 106.68 102.87) (xy 106.68 113.03)
		)
		(stroke
			(width 0)
			(type default)
		)
	)
	(bus
		(pts
			(xy 24.13 179.07) (xy 24.13 181.61)
		)
		(stroke
			(width 0)
			(type default)
		)
	)
	(wire
		(pts
			(xy 55.88 217.17) (xy 73.66 217.17)
		)
		(stroke
			(width 0)
			(type default)
		)
	)
	(wire
		(pts
			(xy 44.45 196.85) (xy 26.67 196.85)
		)
		(stroke
			(width 0)
			(type default)
		)
	)
	(wire
		(pts
			(xy 148.59 49.53) (xy 151.13 49.53)
		)
		(stroke
			(width 0)
			(type default)
		)
	)
	(wire
		(pts
			(xy 300.99 220.98) (xy 300.99 222.25)
		)
		(stroke
			(width 0)
			(type default)
		)
	)
	(wire
		(pts
			(xy 360.68 107.95) (xy 364.49 107.95)
		)
		(stroke
			(width 0)
			(type default)
		)
	)
	(wire
		(pts
			(xy 374.65 118.11) (xy 374.65 111.76)
		)
		(stroke
			(width 0)
			(type default)
		)
	)
	(bus
		(pts
			(xy 163.83 226.06) (xy 163.83 228.6)
		)
		(stroke
			(width 0)
			(type default)
		)
	)
	(wire
		(pts
			(xy 309.88 153.67) (xy 309.88 158.75)
		)
		(stroke
			(width 0)
			(type default)
		)
	)
	(wire
		(pts
			(xy 322.58 109.22) (xy 322.58 107.95)
		)
		(stroke
			(width 0)
			(type default)
		)
	)
	(wire
		(pts
			(xy 360.68 114.3) (xy 360.68 115.57)
		)
		(stroke
			(width 0)
			(type default)
		)
	)
	(wire
		(pts
			(xy 182.88 207.01) (xy 166.37 207.01)
		)
		(stroke
			(width 0)
			(type default)
		)
	)
	(wire
		(pts
			(xy 152.4 109.22) (xy 152.4 111.76)
		)
		(stroke
			(width 0)
			(type default)
		)
	)
	(wire
		(pts
			(xy 266.7 97.79) (xy 266.7 81.28)
		)
		(stroke
			(width 0)
			(type default)
		)
	)
	(wire
		(pts
			(xy 97.79 48.26) (xy 109.22 48.26)
		)
		(stroke
			(width 0)
			(type default)
		)
	)
	(wire
		(pts
			(xy 360.68 121.92) (xy 360.68 123.19)
		)
		(stroke
			(width 0)
			(type default)
		)
	)
	(wire
		(pts
			(xy 55.88 196.85) (xy 73.66 196.85)
		)
		(stroke
			(width 0)
			(type default)
		)
	)
	(wire
		(pts
			(xy 240.03 52.07) (xy 240.03 57.15)
		)
		(stroke
			(width 0)
			(type default)
		)
	)
	(wire
		(pts
			(xy 181.61 217.17) (xy 181.61 218.44)
		)
		(stroke
			(width 0)
			(type default)
		)
	)
	(wire
		(pts
			(xy 44.45 189.23) (xy 43.18 189.23)
		)
		(stroke
			(width 0)
			(type default)
		)
	)
	(wire
		(pts
			(xy 132.08 171.45) (xy 114.3 171.45)
		)
		(stroke
			(width 0)
			(type default)
		)
	)
	(wire
		(pts
			(xy 106.68 113.03) (xy 109.22 113.03)
		)
		(stroke
			(width 0)
			(type default)
		)
	)
	(polyline
		(pts
			(xy 378.46 85.09) (xy 393.7 85.09)
		)
		(stroke
			(width 0.3)
			(type solid)
		)
	)
	(wire
		(pts
			(xy 55.88 181.61) (xy 58.42 181.61)
		)
		(stroke
			(width 0)
			(type default)
		)
	)
	(wire
		(pts
			(xy 345.44 130.81) (xy 345.44 123.19)
		)
		(stroke
			(width 0)
			(type default)
		)
	)
	(wire
		(pts
			(xy 314.96 107.95) (xy 322.58 107.95)
		)
		(stroke
			(width 0)
			(type default)
		)
	)
	(wire
		(pts
			(xy 314.96 130.81) (xy 331.47 130.81)
		)
		(stroke
			(width 0)
			(type default)
		)
	)
	(wire
		(pts
			(xy 331.47 106.68) (xy 331.47 107.95)
		)
		(stroke
			(width 0)
			(type default)
		)
	)
	(wire
		(pts
			(xy 322.58 107.95) (xy 331.47 107.95)
		)
		(stroke
			(width 0)
			(type default)
		)
	)
	(polyline
		(pts
			(xy 12.7 133.35) (xy 210.82 133.35)
		)
		(stroke
			(width 0)
			(type default)
		)
	)
	(wire
		(pts
			(xy 309.88 166.37) (xy 314.96 166.37)
		)
		(stroke
			(width 0)
			(type default)
		)
	)
	(wire
		(pts
			(xy 275.59 143.51) (xy 276.86 143.51)
		)
		(stroke
			(width 0)
			(type default)
		)
	)
	(wire
		(pts
			(xy 240.03 68.58) (xy 240.03 62.23)
		)
		(stroke
			(width 0)
			(type default)
		)
	)
	(polyline
		(pts
			(xy 57.15 165.1) (xy 57.15 157.48)
		)
		(stroke
			(width 0)
			(type default)
		)
	)
	(wire
		(pts
			(xy 318.77 158.75) (xy 320.04 158.75)
		)
		(stroke
			(width 0)
			(type default)
		)
	)
	(wire
		(pts
			(xy 106.68 113.03) (xy 106.68 115.57)
		)
		(stroke
			(width 0)
			(type default)
		)
	)
	(polyline
		(pts
			(xy 210.82 179.07) (xy 407.67 179.07)
		)
		(stroke
			(width 0)
			(type default)
		)
	)
	(wire
		(pts
			(xy 257.81 62.23) (xy 257.81 63.5)
		)
		(stroke
			(width 0)
			(type default)
		)
	)
	(wire
		(pts
			(xy 264.16 137.16) (xy 264.16 140.97)
		)
		(stroke
			(width 0)
			(type default)
		)
	)
	(wire
		(pts
			(xy 331.47 124.46) (xy 331.47 123.19)
		)
		(stroke
			(width 0)
			(type default)
		)
	)
	(bus
		(pts
			(xy 76.2 209.55) (xy 76.2 212.09)
		)
		(stroke
			(width 0)
			(type default)
		)
	)
	(bus
		(pts
			(xy 83.82 101.6) (xy 83.82 102.87)
		)
		(stroke
			(width 0)
			(type default)
		)
	)
	(bus
		(pts
			(xy 163.83 204.47) (xy 163.83 207.01)
		)
		(stroke
			(width 0)
			(type default)
		)
	)
	(wire
		(pts
			(xy 151.13 46.99) (xy 151.13 49.53)
		)
		(stroke
			(width 0)
			(type default)
		)
	)
	(bus
		(pts
			(xy 163.83 184.15) (xy 163.83 186.69)
		)
		(stroke
			(width 0)
			(type default)
		)
	)
	(wire
		(pts
			(xy 182.88 217.17) (xy 181.61 217.17)
		)
		(stroke
			(width 0)
			(type default)
		)
	)
	(bus
		(pts
			(xy 24.13 184.15) (xy 24.13 189.23)
		)
		(stroke
			(width 0)
			(type default)
		)
	)
	(wire
		(pts
			(xy 257.81 74.93) (xy 257.81 76.2)
		)
		(stroke
			(width 0)
			(type default)
		)
	)
	(wire
		(pts
			(xy 307.34 123.19) (xy 309.88 123.19)
		)
		(stroke
			(width 0)
			(type default)
		)
	)
	(bus
		(pts
			(xy 76.2 168.91) (xy 24.13 168.91)
		)
		(stroke
			(width 0)
			(type default)
		)
	)
	(wire
		(pts
			(xy 344.17 123.19) (xy 345.44 123.19)
		)
		(stroke
			(width 0)
			(type default)
		)
	)
	(wire
		(pts
			(xy 243.84 120.65) (xy 243.84 125.73)
		)
		(stroke
			(width 0)
			(type default)
		)
	)
	(wire
		(pts
			(xy 320.04 158.75) (xy 320.04 160.02)
		)
		(stroke
			(width 0)
			(type default)
		)
	)
	(wire
		(pts
			(xy 331.47 123.19) (xy 322.58 123.19)
		)
		(stroke
			(width 0)
			(type default)
		)
	)
	(wire
		(pts
			(xy 41.91 179.07) (xy 44.45 179.07)
		)
		(stroke
			(width 0)
			(type default)
		)
	)
	(wire
		(pts
			(xy 132.08 168.91) (xy 114.3 168.91)
		)
		(stroke
			(width 0)
			(type default)
		)
	)
	(wire
		(pts
			(xy 248.92 55.88) (xy 248.92 57.15)
		)
		(stroke
			(width 0)
			(type default)
		)
	)
	(wire
		(pts
			(xy 55.88 186.69) (xy 73.66 186.69)
		)
		(stroke
			(width 0)
			(type default)
		)
	)
	(wire
		(pts
			(xy 106.68 40.64) (xy 106.68 50.8)
		)
		(stroke
			(width 0)
			(type default)
		)
	)
	(wire
		(pts
			(xy 243.84 125.73) (xy 276.86 125.73)
		)
		(stroke
			(width 0)
			(type default)
		)
	)
	(wire
		(pts
			(xy 132.08 176.53) (xy 130.81 176.53)
		)
		(stroke
			(width 0)
			(type default)
		)
	)
	(polyline
		(pts
			(xy 20.32 157.48) (xy 57.15 157.48)
		)
		(stroke
			(width 0)
			(type default)
		)
	)
	(wire
		(pts
			(xy 331.47 123.19) (xy 337.82 123.19)
		)
		(stroke
			(width 0)
			(type default)
		)
	)
	(bus
		(pts
			(xy 76.2 184.15) (xy 76.2 186.69)
		)
		(stroke
			(width 0)
			(type default)
		)
	)
	(wire
		(pts
			(xy 248.92 210.82) (xy 256.54 210.82)
		)
		(stroke
			(width 0)
			(type default)
		)
	)
	(wire
		(pts
			(xy 350.52 115.57) (xy 350.52 116.84)
		)
		(stroke
			(width 0)
			(type default)
		)
	)
	(bus
		(pts
			(xy 76.2 186.69) (xy 76.2 189.23)
		)
		(stroke
			(width 0)
			(type default)
		)
	)
	(wire
		(pts
			(xy 345.44 107.95) (xy 350.52 107.95)
		)
		(stroke
			(width 0)
			(type default)
		)
	)
	(bus
		(pts
			(xy 76.2 196.85) (xy 76.2 201.93)
		)
		(stroke
			(width 0)
			(type default)
		)
	)
	(wire
		(pts
			(xy 130.81 176.53) (xy 130.81 177.8)
		)
		(stroke
			(width 0)
			(type default)
		)
	)
	(wire
		(pts
			(xy 44.45 214.63) (xy 26.67 214.63)
		)
		(stroke
			(width 0)
			(type default)
		)
	)
	(bus
		(pts
			(xy 163.83 223.52) (xy 163.83 226.06)
		)
		(stroke
			(width 0)
			(type default)
		)
	)
	(wire
		(pts
			(xy 109.22 40.64) (xy 106.68 40.64)
		)
		(stroke
			(width 0)
			(type default)
		)
	)
	(wire
		(pts
			(xy 375.92 111.76) (xy 374.65 111.76)
		)
		(stroke
			(width 0)
			(type default)
		)
	)
	(wire
		(pts
			(xy 369.57 123.19) (xy 372.11 123.19)
		)
		(stroke
			(width 0)
			(type default)
		)
	)
	(wire
		(pts
			(xy 181.61 177.8) (xy 181.61 179.07)
		)
		(stroke
			(width 0)
			(type default)
		)
	)
	(wire
		(pts
			(xy 264.16 140.97) (xy 267.97 140.97)
		)
		(stroke
			(width 0)
			(type default)
		)
	)
	(wire
		(pts
			(xy 182.88 189.23) (xy 166.37 189.23)
		)
		(stroke
			(width 0)
			(type default)
		)
	)
	(wire
		(pts
			(xy 97.79 48.26) (xy 97.79 39.37)
		)
		(stroke
			(width 0)
			(type default)
		)
	)
	(wire
		(pts
			(xy 267.97 137.16) (xy 264.16 137.16)
		)
		(stroke
			(width 0)
			(type default)
		)
	)
	(wire
		(pts
			(xy 149.86 101.6) (xy 162.56 101.6)
		)
		(stroke
			(width 0)
			(type default)
		)
	)
	(bus
		(pts
			(xy 111.76 203.2) (xy 111.76 205.74)
		)
		(stroke
			(width 0)
			(type default)
		)
	)
	(wire
		(pts
			(xy 55.88 212.09) (xy 73.66 212.09)
		)
		(stroke
			(width 0)
			(type default)
		)
	)
	(wire
		(pts
			(xy 314.96 100.33) (xy 331.47 100.33)
		)
		(stroke
			(width 0)
			(type default)
		)
	)
	(wire
		(pts
			(xy 132.08 195.58) (xy 130.81 195.58)
		)
		(stroke
			(width 0)
			(type default)
		)
	)
	(bus
		(pts
			(xy 163.83 35.56) (xy 163.83 36.83)
		)
		(stroke
			(width 0)
			(type default)
		)
	)
	(wire
		(pts
			(xy 264.16 132.08) (xy 267.97 132.08)
		)
		(stroke
			(width 0)
			(type default)
		)
	)
	(wire
		(pts
			(xy 86.36 107.95) (xy 109.22 107.95)
		)
		(stroke
			(width 0)
			(type default)
		)
	)
	(wire
		(pts
			(xy 248.92 212.09) (xy 248.92 210.82)
		)
		(stroke
			(width 0)
			(type default)
		)
	)
	(wire
		(pts
			(xy 55.88 224.79) (xy 73.66 224.79)
		)
		(stroke
			(width 0)
			(type default)
		)
	)
	(wire
		(pts
			(xy 320.04 151.13) (xy 307.34 151.13)
		)
		(stroke
			(width 0)
			(type default)
		)
	)
	(wire
		(pts
			(xy 350.52 121.92) (xy 350.52 123.19)
		)
		(stroke
			(width 0)
			(type default)
		)
	)
	(wire
		(pts
			(xy 151.13 44.45) (xy 148.59 44.45)
		)
		(stroke
			(width 0)
			(type default)
		)
	)
	(bus
		(pts
			(xy 163.83 36.83) (xy 163.83 39.37)
		)
		(stroke
			(width 0)
			(type default)
		)
	)
	(wire
		(pts
			(xy 91.44 90.17) (xy 91.44 91.44)
		)
		(stroke
			(width 0)
			(type default)
		)
	)
	(wire
		(pts
			(xy 248.92 55.88) (xy 257.81 55.88)
		)
		(stroke
			(width 0)
			(type default)
		)
	)
	(wire
		(pts
			(xy 86.36 43.18) (xy 109.22 43.18)
		)
		(stroke
			(width 0)
			(type default)
		)
	)
	(wire
		(pts
			(xy 236.22 132.08) (xy 236.22 133.35)
		)
		(stroke
			(width 0)
			(type default)
		)
	)
	(wire
		(pts
			(xy 44.45 217.17) (xy 26.67 217.17)
		)
		(stroke
			(width 0)
			(type default)
		)
	)
	(wire
		(pts
			(xy 130.81 234.95) (xy 130.81 236.22)
		)
		(stroke
			(width 0)
			(type default)
		)
	)
	(wire
		(pts
			(xy 248.92 52.07) (xy 248.92 55.88)
		)
		(stroke
			(width 0)
			(type default)
		)
	)
	(bus
		(pts
			(xy 111.76 224.79) (xy 111.76 227.33)
		)
		(stroke
			(width 0)
			(type default)
		)
	)
	(wire
		(pts
			(xy 182.88 177.8) (xy 181.61 177.8)
		)
		(stroke
			(width 0)
			(type default)
		)
	)
	(wire
		(pts
			(xy 372.11 107.95) (xy 372.11 114.3)
		)
		(stroke
			(width 0)
			(type default)
		)
	)
	(wire
		(pts
			(xy 151.13 49.53) (xy 151.13 52.07)
		)
		(stroke
			(width 0)
			(type default)
		)
	)
	(wire
		(pts
			(xy 345.44 123.19) (xy 350.52 123.19)
		)
		(stroke
			(width 0)
			(type default)
		)
	)
	(bus
		(pts
			(xy 111.76 185.42) (xy 111.76 187.96)
		)
		(stroke
			(width 0)
			(type default)
		)
	)
	(wire
		(pts
			(xy 58.42 181.61) (xy 58.42 179.07)
		)
		(stroke
			(width 0)
			(type default)
		)
	)
	(wire
		(pts
			(xy 55.88 219.71) (xy 58.42 219.71)
		)
		(stroke
			(width 0)
			(type default)
		)
	)
	(wire
		(pts
			(xy 248.92 81.28) (xy 257.81 81.28)
		)
		(stroke
			(width 0)
			(type default)
		)
	)
	(polyline
		(pts
			(xy 392.43 86.36) (xy 392.43 105.41)
		)
		(stroke
			(width 0.3)
			(type solid)
		)
	)
	(wire
		(pts
			(xy 275.59 134.62) (xy 276.86 134.62)
		)
		(stroke
			(width 0)
			(type default)
		)
	)
	(wire
		(pts
			(xy 337.82 130.81) (xy 339.09 130.81)
		)
		(stroke
			(width 0)
			(type default)
		)
	)
	(wire
		(pts
			(xy 151.13 35.56) (xy 151.13 44.45)
		)
		(stroke
			(width 0)
			(type default)
		)
	)
	(wire
		(pts
			(xy 307.34 153.67) (xy 309.88 153.67)
		)
		(stroke
			(width 0)
			(type default)
		)
	)
	(wire
		(pts
			(xy 257.81 231.14) (xy 256.54 231.14)
		)
		(stroke
			(width 0)
			(type default)
		)
	)
	(polyline
		(pts
			(xy 210.82 12.7) (xy 210.82 284.48)
		)
		(stroke
			(width 0)
			(type default)
		)
	)
	(bus
		(pts
			(xy 111.76 210.82) (xy 111.76 222.25)
		)
		(stroke
			(width 0)
			(type default)
		)
	)
	(wire
		(pts
			(xy 182.88 186.69) (xy 166.37 186.69)
		)
		(stroke
			(width 0)
			(type default)
		)
	)
	(wire
		(pts
			(xy 181.61 196.85) (xy 181.61 198.12)
		)
		(stroke
			(width 0)
			(type default)
		)
	)
	(bus
		(pts
			(xy 255.27 97.79) (xy 255.27 100.33)
		)
		(stroke
			(width 0)
			(type default)
		)
	)
	(bus
		(pts
			(xy 111.76 222.25) (xy 111.76 224.79)
		)
		(stroke
			(width 0)
			(type default)
		)
	)
	(bus
		(pts
			(xy 76.2 214.63) (xy 76.2 219.71)
		)
		(stroke
			(width 0)
			(type default)
		)
	)
	(wire
		(pts
			(xy 346.71 115.57) (xy 346.71 116.84)
		)
		(stroke
			(width 0)
			(type default)
		)
	)
	(wire
		(pts
			(xy 257.81 81.28) (xy 266.7 81.28)
		)
		(stroke
			(width 0)
			(type default)
		)
	)
	(wire
		(pts
			(xy 360.68 123.19) (xy 364.49 123.19)
		)
		(stroke
			(width 0)
			(type default)
		)
	)
	(wire
		(pts
			(xy 309.88 158.75) (xy 309.88 160.02)
		)
		(stroke
			(width 0)
			(type default)
		)
	)
	(wire
		(pts
			(xy 55.88 201.93) (xy 58.42 201.93)
		)
		(stroke
			(width 0)
			(type default)
		)
	)
	(wire
		(pts
			(xy 246.38 223.52) (xy 257.81 223.52)
		)
		(stroke
			(width 0)
			(type default)
		)
	)
	(wire
		(pts
			(xy 149.86 109.22) (xy 152.4 109.22)
		)
		(stroke
			(width 0)
			(type default)
		)
	)
	(wire
		(pts
			(xy 264.16 140.97) (xy 264.16 146.05)
		)
		(stroke
			(width 0)
			(type default)
		)
	)
	(wire
		(pts
			(xy 275.59 109.22) (xy 276.86 109.22)
		)
		(stroke
			(width 0)
			(type default)
		)
	)
	(wire
		(pts
			(xy 289.56 228.6) (xy 289.56 231.14)
		)
		(stroke
			(width 0)
			(type default)
		)
	)
	(wire
		(pts
			(xy 166.37 194.31) (xy 182.88 194.31)
		)
		(stroke
			(width 0)
			(type default)
		)
	)
	(wire
		(pts
			(xy 372.11 123.19) (xy 372.11 116.84)
		)
		(stroke
			(width 0)
			(type default)
		)
	)
	(wire
		(pts
			(xy 248.92 68.58) (xy 257.81 68.58)
		)
		(stroke
			(width 0)
			(type default)
		)
	)
	(bus
		(pts
			(xy 83.82 102.87) (xy 83.82 105.41)
		)
		(stroke
			(width 0)
			(type default)
		)
	)
	(wire
		(pts
			(xy 275.59 137.16) (xy 276.86 137.16)
		)
		(stroke
			(width 0)
			(type default)
		)
	)
	(wire
		(pts
			(xy 132.08 227.33) (xy 114.3 227.33)
		)
		(stroke
			(width 0)
			(type default)
		)
	)
	(wire
		(pts
			(xy 106.68 50.8) (xy 109.22 50.8)
		)
		(stroke
			(width 0)
			(type default)
		)
	)
	(wire
		(pts
			(xy 58.42 179.07) (xy 58.42 177.8)
		)
		(stroke
			(width 0)
			(type default)
		)
	)
	(wire
		(pts
			(xy 275.59 153.67) (xy 275.59 157.48)
		)
		(stroke
			(width 0)
			(type default)
		)
	)
	(wire
		(pts
			(xy 269.24 95.25) (xy 269.24 68.58)
		)
		(stroke
			(width 0)
			(type default)
		)
	)
	(polyline
		(pts
			(xy 394.97 102.87) (xy 378.46 102.87)
		)
		(stroke
			(width 0.3)
			(type solid)
		)
	)
	(bus
		(pts
			(xy 78.74 168.91) (xy 76.2 168.91)
		)
		(stroke
			(width 0)
			(type default)
		)
	)
	(wire
		(pts
			(xy 182.88 212.09) (xy 166.37 212.09)
		)
		(stroke
			(width 0)
			(type default)
		)
	)
	(bus
		(pts
			(xy 111.76 168.91) (xy 111.76 171.45)
		)
		(stroke
			(width 0)
			(type default)
		)
	)
	(wire
		(pts
			(xy 307.34 92.71) (xy 309.88 92.71)
		)
		(stroke
			(width 0)
			(type default)
		)
	)
	(wire
		(pts
			(xy 322.58 114.3) (xy 322.58 115.57)
		)
		(stroke
			(width 0)
			(type default)
		)
	)
	(wire
		(pts
			(xy 44.45 181.61) (xy 26.67 181.61)
		)
		(stroke
			(width 0)
			(type default)
		)
	)
	(wire
		(pts
			(xy 96.52 90.17) (xy 96.52 91.44)
		)
		(stroke
			(width 0)
			(type default)
		)
	)
	(bus
		(pts
			(xy 111.76 182.88) (xy 111.76 185.42)
		)
		(stroke
			(width 0)
			(type default)
		)
	)
	(bus
		(pts
			(xy 76.2 194.31) (xy 76.2 196.85)
		)
		(stroke
			(width 0)
			(type default)
		)
	)
	(wire
		(pts
			(xy 55.88 204.47) (xy 73.66 204.47)
		)
		(stroke
			(width 0)
			(type default)
		)
	)
	(wire
		(pts
			(xy 275.59 146.05) (xy 276.86 146.05)
		)
		(stroke
			(width 0)
			(type default)
		)
	)
	(wire
		(pts
			(xy 44.45 207.01) (xy 26.67 207.01)
		)
		(stroke
			(width 0)
			(type default)
		)
	)
	(wire
		(pts
			(xy 267.97 146.05) (xy 264.16 146.05)
		)
		(stroke
			(width 0)
			(type default)
		)
	)
	(wire
		(pts
			(xy 317.5 115.57) (xy 317.5 116.84)
		)
		(stroke
			(width 0)
			(type default)
		)
	)
	(wire
		(pts
			(xy 55.88 184.15) (xy 58.42 184.15)
		)
		(stroke
			(width 0)
			(type default)
		)
	)
	(bus
		(pts
			(xy 24.13 189.23) (xy 24.13 191.77)
		)
		(stroke
			(width 0)
			(type default)
		)
	)
	(wire
		(pts
			(xy 276.86 153.67) (xy 275.59 153.67)
		)
		(stroke
			(width 0)
			(type default)
		)
	)
	(polyline
		(pts
			(xy 377.19 104.14) (xy 378.46 104.14)
		)
		(stroke
			(width 0.3)
			(type solid)
		)
	)
	(wire
		(pts
			(xy 248.92 209.55) (xy 248.92 210.82)
		)
		(stroke
			(width 0)
			(type default)
		)
	)
	(wire
		(pts
			(xy 166.37 175.26) (xy 182.88 175.26)
		)
		(stroke
			(width 0)
			(type default)
		)
	)
	(wire
		(pts
			(xy 109.22 102.87) (xy 106.68 102.87)
		)
		(stroke
			(width 0)
			(type default)
		)
	)
	(wire
		(pts
			(xy 322.58 115.57) (xy 331.47 115.57)
		)
		(stroke
			(width 0)
			(type default)
		)
	)
	(wire
		(pts
			(xy 337.82 107.95) (xy 339.09 107.95)
		)
		(stroke
			(width 0)
			(type default)
		)
	)
	(wire
		(pts
			(xy 166.37 170.18) (xy 182.88 170.18)
		)
		(stroke
			(width 0)
			(type default)
		)
	)
	(bus
		(pts
			(xy 76.2 219.71) (xy 76.2 222.25)
		)
		(stroke
			(width 0)
			(type default)
		)
	)
	(wire
		(pts
			(xy 344.17 100.33) (xy 345.44 100.33)
		)
		(stroke
			(width 0)
			(type default)
		)
	)
	(wire
		(pts
			(xy 360.68 92.71) (xy 360.68 107.95)
		)
		(stroke
			(width 0)
			(type default)
		)
	)
	(wire
		(pts
			(xy 257.81 87.63) (xy 257.81 88.9)
		)
		(stroke
			(width 0)
			(type default)
		)
	)
	(wire
		(pts
			(xy 331.47 130.81) (xy 331.47 129.54)
		)
		(stroke
			(width 0)
			(type default)
		)
	)
	(wire
		(pts
			(xy 96.52 100.33) (xy 96.52 96.52)
		)
		(stroke
			(width 0)
			(type default)
		)
	)
	(bus
		(pts
			(xy 24.13 201.93) (xy 24.13 204.47)
		)
		(stroke
			(width 0)
			(type default)
		)
	)
	(wire
		(pts
			(xy 314.96 92.71) (xy 360.68 92.71)
		)
		(stroke
			(width 0)
			(type default)
		)
	)
	(wire
		(pts
			(xy 246.38 226.06) (xy 257.81 226.06)
		)
		(stroke
			(width 0)
			(type default)
		)
	)
	(bus
		(pts
			(xy 163.83 167.64) (xy 163.83 170.18)
		)
		(stroke
			(width 0)
			(type default)
		)
	)
	(wire
		(pts
			(xy 256.54 231.14) (xy 256.54 232.41)
		)
		(stroke
			(width 0)
			(type default)
		)
	)
	(wire
		(pts
			(xy 344.17 130.81) (xy 345.44 130.81)
		)
		(stroke
			(width 0)
			(type default)
		)
	)
	(wire
		(pts
			(xy 132.08 224.79) (xy 114.3 224.79)
		)
		(stroke
			(width 0)
			(type default)
		)
	)
	(wire
		(pts
			(xy 350.52 114.3) (xy 350.52 115.57)
		)
		(stroke
			(width 0)
			(type default)
		)
	)
	(wire
		(pts
			(xy 236.22 123.19) (xy 276.86 123.19)
		)
		(stroke
			(width 0)
			(type default)
		)
	)
	(bus
		(pts
			(xy 24.13 212.09) (xy 24.13 214.63)
		)
		(stroke
			(width 0)
			(type default)
		)
	)
	(wire
		(pts
			(xy 44.45 209.55) (xy 43.18 209.55)
		)
		(stroke
			(width 0)
			(type default)
		)
	)
	(bus
		(pts
			(xy 163.83 228.6) (xy 163.83 231.14)
		)
		(stroke
			(width 0)
			(type default)
		)
	)
	(bus
		(pts
			(xy 165.1 97.79) (xy 165.1 99.06)
		)
		(stroke
			(width 0)
			(type default)
		)
	)
	(bus
		(pts
			(xy 111.76 205.74) (xy 111.76 208.28)
		)
		(stroke
			(width 0)
			(type default)
		)
	)
	(wire
		(pts
			(xy 271.78 92.71) (xy 276.86 92.71)
		)
		(stroke
			(width 0)
			(type default)
		)
	)
	(bus
		(pts
			(xy 76.2 189.23) (xy 76.2 191.77)
		)
		(stroke
			(width 0)
			(type default)
		)
	)
	(wire
		(pts
			(xy 256.54 220.98) (xy 257.81 220.98)
		)
		(stroke
			(width 0)
			(type default)
		)
	)
	(bus
		(pts
			(xy 24.13 168.91) (xy 24.13 179.07)
		)
		(stroke
			(width 0)
			(type default)
		)
	)
	(wire
		(pts
			(xy 158.75 106.68) (xy 149.86 106.68)
		)
		(stroke
			(width 0)
			(type default)
		)
	)
	(wire
		(pts
			(xy 236.22 123.19) (xy 236.22 127)
		)
		(stroke
			(width 0)
			(type default)
		)
	)
	(wire
		(pts
			(xy 314.96 123.19) (xy 322.58 123.19)
		)
		(stroke
			(width 0)
			(type default)
		)
	)
	(bus
		(pts
			(xy 111.76 208.28) (xy 111.76 210.82)
		)
		(stroke
			(width 0)
			(type default)
		)
	)
	(polyline
		(pts
			(xy 377.19 99.06) (xy 377.19 83.82)
		)
		(stroke
			(width 0.3)
			(type solid)
		)
	)
	(wire
		(pts
			(xy 275.59 140.97) (xy 276.86 140.97)
		)
		(stroke
			(width 0)
			(type default)
		)
	)
	(wire
		(pts
			(xy 264.16 149.86) (xy 264.16 157.48)
		)
		(stroke
			(width 0)
			(type default)
		)
	)
	(bus
		(pts
			(xy 163.83 191.77) (xy 163.83 204.47)
		)
		(stroke
			(width 0)
			(type default)
		)
	)
	(wire
		(pts
			(xy 331.47 115.57) (xy 331.47 116.84)
		)
		(stroke
			(width 0)
			(type default)
		)
	)
	(wire
		(pts
			(xy 55.88 222.25) (xy 73.66 222.25)
		)
		(stroke
			(width 0)
			(type default)
		)
	)
	(wire
		(pts
			(xy 44.45 222.25) (xy 26.67 222.25)
		)
		(stroke
			(width 0)
			(type default)
		)
	)
	(wire
		(pts
			(xy 181.61 163.83) (xy 181.61 167.64)
		)
		(stroke
			(width 0)
			(type default)
		)
	)
	(bus
		(pts
			(xy 165.1 99.06) (xy 165.1 101.6)
		)
		(stroke
			(width 0)
			(type default)
		)
	)
	(wire
		(pts
			(xy 148.59 39.37) (xy 161.29 39.37)
		)
		(stroke
			(width 0)
			(type default)
		)
	)
	(wire
		(pts
			(xy 44.45 224.79) (xy 26.67 224.79)
		)
		(stroke
			(width 0)
			(type default)
		)
	)
	(wire
		(pts
			(xy 256.54 101.6) (xy 276.86 101.6)
		)
		(stroke
			(width 0)
			(type default)
		)
	)
	(bus
		(pts
			(xy 76.2 204.47) (xy 76.2 207.01)
		)
		(stroke
			(width 0)
			(type default)
		)
	)
	(wire
		(pts
			(xy 264.16 132.08) (xy 264.16 137.16)
		)
		(stroke
			(width 0)
			(type default)
		)
	)
	(wire
		(pts
			(xy 278.13 231.14) (xy 280.67 231.14)
		)
		(stroke
			(width 0)
			(type default)
		)
	)
	(wire
		(pts
			(xy 43.18 189.23) (xy 43.18 209.55)
		)
		(stroke
			(width 0)
			(type default)
		)
	)
	(wire
		(pts
			(xy 182.88 233.68) (xy 166.37 233.68)
		)
		(stroke
			(width 0)
			(type default)
		)
	)
	(wire
		(pts
			(xy 132.08 190.5) (xy 114.3 190.5)
		)
		(stroke
			(width 0)
			(type default)
		)
	)
	(bus
		(pts
			(xy 76.2 191.77) (xy 76.2 194.31)
		)
		(stroke
			(width 0)
			(type default)
		)
	)
	(polyline
		(pts
			(xy 377.19 104.14) (xy 389.89 104.14)
		)
		(stroke
			(width 0.3)
			(type solid)
		)
	)
	(wire
		(pts
			(xy 314.96 163.83) (xy 314.96 166.37)
		)
		(stroke
			(width 0)
			(type default)
		)
	)
	(wire
		(pts
			(xy 44.45 199.39) (xy 41.91 199.39)
		)
		(stroke
			(width 0)
			(type default)
		)
	)
	(wire
		(pts
			(xy 132.08 187.96) (xy 114.3 187.96)
		)
		(stroke
			(width 0)
			(type default)
		)
	)
	(wire
		(pts
			(xy 337.82 123.19) (xy 339.09 123.19)
		)
		(stroke
			(width 0)
			(type default)
		)
	)
	(wire
		(pts
			(xy 149.86 104.14) (xy 162.56 104.14)
		)
		(stroke
			(width 0)
			(type default)
		)
	)
	(wire
		(pts
			(xy 132.08 229.87) (xy 114.3 229.87)
		)
		(stroke
			(width 0)
			(type default)
		)
	)
	(wire
		(pts
			(xy 331.47 121.92) (xy 331.47 123.19)
		)
		(stroke
			(width 0)
			(type default)
		)
	)
	(wire
		(pts
			(xy 331.47 107.95) (xy 337.82 107.95)
		)
		(stroke
			(width 0)
			(type default)
		)
	)
	(wire
		(pts
			(xy 350.52 123.19) (xy 360.68 123.19)
		)
		(stroke
			(width 0)
			(type default)
		)
	)
	(polyline
		(pts
			(xy 377.19 99.06) (xy 377.19 104.14)
		)
		(stroke
			(width 0.3)
			(type solid)
		)
	)
	(wire
		(pts
			(xy 309.88 158.75) (xy 311.15 158.75)
		)
		(stroke
			(width 0)
			(type default)
		)
	)
	(bus
		(pts
			(xy 24.13 219.71) (xy 24.13 222.25)
		)
		(stroke
			(width 0)
			(type default)
		)
	)
	(polyline
		(pts
			(xy 222.25 139.7) (xy 222.25 156.21)
		)
		(stroke
			(width 0)
			(type default)
		)
	)
	(wire
		(pts
			(xy 182.88 209.55) (xy 166.37 209.55)
		)
		(stroke
			(width 0)
			(type default)
		)
	)
	(wire
		(pts
			(xy 275.59 140.97) (xy 275.59 143.51)
		)
		(stroke
			(width 0)
			(type default)
		)
	)
	(wire
		(pts
			(xy 257.81 68.58) (xy 257.81 69.85)
		)
		(stroke
			(width 0)
			(type default)
		)
	)
	(wire
		(pts
			(xy 273.05 132.08) (xy 275.59 132.08)
		)
		(stroke
			(width 0)
			(type default)
		)
	)
	(wire
		(pts
			(xy 152.4 111.76) (xy 152.4 114.3)
		)
		(stroke
			(width 0)
			(type default)
		)
	)
	(wire
		(pts
			(xy 322.58 121.92) (xy 322.58 123.19)
		)
		(stroke
			(width 0)
			(type default)
		)
	)
	(wire
		(pts
			(xy 289.56 231.14) (xy 288.29 231.14)
		)
		(stroke
			(width 0)
			(type default)
		)
	)
	(wire
		(pts
			(xy 132.08 232.41) (xy 114.3 232.41)
		)
		(stroke
			(width 0)
			(type default)
		)
	)
	(wire
		(pts
			(xy 41.91 179.07) (xy 41.91 199.39)
		)
		(stroke
			(width 0)
			(type default)
		)
	)
	(wire
		(pts
			(xy 148.59 46.99) (xy 151.13 46.99)
		)
		(stroke
			(width 0)
			(type default)
		)
	)
	(wire
		(pts
			(xy 58.42 219.71) (xy 58.42 228.6)
		)
		(stroke
			(width 0)
			(type default)
		)
	)
	(wire
		(pts
			(xy 276.86 132.08) (xy 275.59 132.08)
		)
		(stroke
			(width 0)
			(type default)
		)
	)
	(wire
		(pts
			(xy 350.52 115.57) (xy 360.68 115.57)
		)
		(stroke
			(width 0)
			(type default)
		)
	)
	(wire
		(pts
			(xy 243.84 125.73) (xy 243.84 127)
		)
		(stroke
			(width 0)
			(type default)
		)
	)
	(wire
		(pts
			(xy 182.88 191.77) (xy 166.37 191.77)
		)
		(stroke
			(width 0)
			(type default)
		)
	)
	(wire
		(pts
			(xy 248.92 68.58) (xy 248.92 81.28)
		)
		(stroke
			(width 0)
			(type default)
		)
	)
	(wire
		(pts
			(xy 132.08 173.99) (xy 114.3 173.99)
		)
		(stroke
			(width 0)
			(type default)
		)
	)
	(wire
		(pts
			(xy 278.13 228.6) (xy 289.56 228.6)
		)
		(stroke
			(width 0)
			(type default)
		)
	)
	(wire
		(pts
			(xy 248.92 87.63) (xy 248.92 88.9)
		)
		(stroke
			(width 0)
			(type default)
		)
	)
	(wire
		(pts
			(xy 43.18 209.55) (xy 43.18 227.33)
		)
		(stroke
			(width 0)
			(type default)
		)
	)
	(wire
		(pts
			(xy 256.54 111.76) (xy 276.86 111.76)
		)
		(stroke
			(width 0)
			(type default)
		)
	)
	(wire
		(pts
			(xy 132.08 234.95) (xy 130.81 234.95)
		)
		(stroke
			(width 0)
			(type default)
		)
	)
	(wire
		(pts
			(xy 55.88 207.01) (xy 73.66 207.01)
		)
		(stroke
			(width 0)
			(type default)
		)
	)
	(wire
		(pts
			(xy 236.22 114.3) (xy 236.22 115.57)
		)
		(stroke
			(width 0)
			(type default)
		)
	)
	(bus
		(pts
			(xy 76.2 168.91) (xy 76.2 184.15)
		)
		(stroke
			(width 0)
			(type default)
		)
	)
	(wire
		(pts
			(xy 132.08 215.9) (xy 130.81 215.9)
		)
		(stroke
			(width 0)
			(type default)
		)
	)
	(bus
		(pts
			(xy 111.76 165.1) (xy 111.76 166.37)
		)
		(stroke
			(width 0)
			(type default)
		)
	)
	(polyline
		(pts
			(xy 259.08 156.21) (xy 259.08 139.7)
		)
		(stroke
			(width 0)
			(type default)
		)
	)
	(bus
		(pts
			(xy 163.83 186.69) (xy 163.83 189.23)
		)
		(stroke
			(width 0)
			(type default)
		)
	)
	(wire
		(pts
			(xy 372.11 116.84) (xy 375.92 116.84)
		)
		(stroke
			(width 0)
			(type default)
		)
	)
	(wire
		(pts
			(xy 55.88 209.55) (xy 73.66 209.55)
		)
		(stroke
			(width 0)
			(type default)
		)
	)
	(wire
		(pts
			(xy 369.57 107.95) (xy 372.11 107.95)
		)
		(stroke
			(width 0)
			(type default)
		)
	)
	(wire
		(pts
			(xy 55.88 227.33) (xy 73.66 227.33)
		)
		(stroke
			(width 0)
			(type default)
		)
	)
	(bus
		(pts
			(xy 111.76 187.96) (xy 111.76 190.5)
		)
		(stroke
			(width 0)
			(type default)
		)
	)
	(wire
		(pts
			(xy 44.45 212.09) (xy 26.67 212.09)
		)
		(stroke
			(width 0)
			(type default)
		)
	)
	(wire
		(pts
			(xy 55.88 194.31) (xy 73.66 194.31)
		)
		(stroke
			(width 0)
			(type default)
		)
	)
	(wire
		(pts
			(xy 331.47 107.95) (xy 331.47 109.22)
		)
		(stroke
			(width 0)
			(type default)
		)
	)
	(bus
		(pts
			(xy 163.83 207.01) (xy 163.83 209.55)
		)
		(stroke
			(width 0)
			(type default)
		)
	)
	(wire
		(pts
			(xy 331.47 114.3) (xy 331.47 115.57)
		)
		(stroke
			(width 0)
			(type default)
		)
	)
	(bus
		(pts
			(xy 24.13 204.47) (xy 24.13 209.55)
		)
		(stroke
			(width 0)
			(type default)
		)
	)
	(wire
		(pts
			(xy 271.78 55.88) (xy 257.81 55.88)
		)
		(stroke
			(width 0)
			(type default)
		)
	)
	(wire
		(pts
			(xy 269.24 95.25) (xy 276.86 95.25)
		)
		(stroke
			(width 0)
			(type default)
		)
	)
	(wire
		(pts
			(xy 44.45 219.71) (xy 26.67 219.71)
		)
		(stroke
			(width 0)
			(type default)
		)
	)
	(bus
		(pts
			(xy 111.76 171.45) (xy 111.76 182.88)
		)
		(stroke
			(width 0)
			(type default)
		)
	)
	(wire
		(pts
			(xy 182.88 196.85) (xy 181.61 196.85)
		)
		(stroke
			(width 0)
			(type default)
		)
	)
	(wire
		(pts
			(xy 130.81 215.9) (xy 130.81 217.17)
		)
		(stroke
			(width 0)
			(type default)
		)
	)
	(bus
		(pts
			(xy 24.13 191.77) (xy 24.13 194.31)
		)
		(stroke
			(width 0)
			(type default)
		)
	)
	(wire
		(pts
			(xy 55.88 191.77) (xy 73.66 191.77)
		)
		(stroke
			(width 0)
			(type default)
		)
	)
	(wire
		(pts
			(xy 360.68 107.95) (xy 360.68 109.22)
		)
		(stroke
			(width 0)
			(type default)
		)
	)
	(wire
		(pts
			(xy 44.45 184.15) (xy 26.67 184.15)
		)
		(stroke
			(width 0)
			(type default)
		)
	)
	(bus
		(pts
			(xy 255.27 100.33) (xy 255.27 105.41)
		)
		(stroke
			(width 0)
			(type default)
		)
	)
	(polyline
		(pts
			(xy 378.46 102.87) (xy 378.46 85.09)
		)
		(stroke
			(width 0.3)
			(type solid)
		)
	)
	(wire
		(pts
			(xy 148.59 41.91) (xy 161.29 41.91)
		)
		(stroke
			(width 0)
			(type default)
		)
	)
	(wire
		(pts
			(xy 55.88 189.23) (xy 73.66 189.23)
		)
		(stroke
			(width 0)
			(type default)
		)
	)
	(wire
		(pts
			(xy 44.45 201.93) (xy 26.67 201.93)
		)
		(stroke
			(width 0)
			(type default)
		)
	)
	(wire
		(pts
			(xy 266.7 97.79) (xy 276.86 97.79)
		)
		(stroke
			(width 0)
			(type default)
		)
	)
	(bus
		(pts
			(xy 76.2 222.25) (xy 76.2 224.79)
		)
		(stroke
			(width 0)
			(type default)
		)
	)
	(wire
		(pts
			(xy 132.08 205.74) (xy 114.3 205.74)
		)
		(stroke
			(width 0)
			(type default)
		)
	)
	(bus
		(pts
			(xy 76.2 201.93) (xy 76.2 204.47)
		)
		(stroke
			(width 0)
			(type default)
		)
	)
	(bus
		(pts
			(xy 163.83 209.55) (xy 163.83 212.09)
		)
		(stroke
			(width 0)
			(type default)
		)
	)
	(wire
		(pts
			(xy 243.84 132.08) (xy 243.84 133.35)
		)
		(stroke
			(width 0)
			(type default)
		)
	)
	(bus
		(pts
			(xy 111.76 190.5) (xy 111.76 203.2)
		)
		(stroke
			(width 0)
			(type default)
		)
	)
	(wire
		(pts
			(xy 181.61 236.22) (xy 181.61 237.49)
		)
		(stroke
			(width 0)
			(type default)
		)
	)
	(wire
		(pts
			(xy 86.36 45.72) (xy 109.22 45.72)
		)
		(stroke
			(width 0)
			(type default)
		)
	)
	(wire
		(pts
			(xy 271.78 92.71) (xy 271.78 55.88)
		)
		(stroke
			(width 0)
			(type default)
		)
	)
	(wire
		(pts
			(xy 269.24 68.58) (xy 257.81 68.58)
		)
		(stroke
			(width 0)
			(type default)
		)
	)
	(wire
		(pts
			(xy 322.58 115.57) (xy 317.5 115.57)
		)
		(stroke
			(width 0)
			(type default)
		)
	)
	(wire
		(pts
			(xy 314.96 166.37) (xy 314.96 167.64)
		)
		(stroke
			(width 0)
			(type default)
		)
	)
	(wire
		(pts
			(xy 307.34 107.95) (xy 309.88 107.95)
		)
		(stroke
			(width 0)
			(type default)
		)
	)
	(bus
		(pts
			(xy 24.13 194.31) (xy 24.13 199.39)
		)
		(stroke
			(width 0)
			(type default)
		)
	)
	(wire
		(pts
			(xy 337.82 123.19) (xy 337.82 130.81)
		)
		(stroke
			(width 0)
			(type default)
		)
	)
	(wire
		(pts
			(xy 267.97 118.11) (xy 276.86 118.11)
		)
		(stroke
			(width 0)
			(type default)
		)
	)
	(wire
		(pts
			(xy 360.68 138.43) (xy 360.68 123.19)
		)
		(stroke
			(width 0)
			(type default)
		)
	)
	(polyline
		(pts
			(xy 222.25 139.7) (xy 259.08 139.7)
		)
		(stroke
			(width 0)
			(type default)
		)
	)
	(wire
		(pts
			(xy 43.18 228.6) (xy 43.18 227.33)
		)
		(stroke
			(width 0)
			(type default)
		)
	)
	(polyline
		(pts
			(xy 389.89 104.14) (xy 389.89 105.41)
		)
		(stroke
			(width 0.3)
			(type solid)
		)
	)
	(wire
		(pts
			(xy 267.97 149.86) (xy 264.16 149.86)
		)
		(stroke
			(width 0)
			(type default)
		)
	)
	(wire
		(pts
			(xy 149.86 111.76) (xy 152.4 111.76)
		)
		(stroke
			(width 0)
			(type default)
		)
	)
	(polyline
		(pts
			(xy 393.7 85.09) (xy 393.7 101.6)
		)
		(stroke
			(width 0.3)
			(type solid)
		)
	)
	(wire
		(pts
			(xy 181.61 167.64) (xy 182.88 167.64)
		)
		(stroke
			(width 0)
			(type default)
		)
	)
	(polyline
		(pts
			(xy 379.73 101.6) (xy 379.73 86.36)
		)
		(stroke
			(width 0.3)
			(type solid)
		)
	)
	(label "I_{2}C1.SCL"
		(at 161.29 39.37 180)
		(effects
			(font
				(size 1.27 1.27)
			)
			(justify right bottom)
		)
	)
	(label "GPIO.11"
		(at 40.64 207.01 180)
		(effects
			(font
				(size 1.27 1.27)
			)
			(justify right bottom)
		)
	)
	(label "GPIO.16"
		(at 59.69 222.25 0)
		(effects
			(font
				(size 1.27 1.27)
			)
			(justify left bottom)
		)
	)
	(label "GPIO.25"
		(at 59.69 204.47 0)
		(effects
			(font
				(size 1.27 1.27)
			)
			(justify left bottom)
		)
	)
	(label "I_{2}C1.SDA"
		(at 161.29 41.91 180)
		(effects
			(font
				(size 1.27 1.27)
			)
			(justify right bottom)
		)
	)
	(label "I_{2}C1.SCL"
		(at 267.97 118.11 0)
		(effects
			(font
				(size 1.27 1.27)
			)
			(justify left bottom)
		)
	)
	(label "I_{2}C1.SDA"
		(at 267.97 120.65 0)
		(effects
			(font
				(size 1.27 1.27)
			)
			(justify left bottom)
		)
	)
	(label "I_{2}C1.SDA"
		(at 86.36 45.72 0)
		(effects
			(font
				(size 1.27 1.27)
			)
			(justify left bottom)
		)
	)
	(label "GPIO.7"
		(at 59.69 209.55 0)
		(effects
			(font
				(size 1.27 1.27)
			)
			(justify left bottom)
		)
	)
	(label "GPIO.0{slash}SDA0"
		(at 40.64 212.09 180)
		(effects
			(font
				(size 1.27 1.27)
			)
			(justify right bottom)
		)
	)
	(label "NFC.DWL_REQ"
		(at 256.54 128.27 0)
		(effects
			(font
				(size 1.27 1.27)
			)
			(justify left bottom)
		)
	)
	(label "GPIO.21"
		(at 59.69 227.33 0)
		(effects
			(font
				(size 1.27 1.27)
			)
			(justify left bottom)
		)
	)
	(label "GPIO.22"
		(at 40.64 196.85 180)
		(effects
			(font
				(size 1.27 1.27)
			)
			(justify right bottom)
		)
	)
	(label "GPIO.18"
		(at 180.34 175.26 180)
		(effects
			(font
				(size 1.27 1.27)
			)
			(justify right bottom)
		)
	)
	(label "GPIO.13/TXD5"
		(at 40.64 219.71 180)
		(effects
			(font
				(size 1.27 1.27)
			)
			(justify right bottom)
		)
	)
	(label "GPIO.8/TXD4"
		(at 59.69 207.01 0)
		(effects
			(font
				(size 1.27 1.27)
			)
			(justify left bottom)
		)
	)
	(label "GPIO.15/TXD0"
		(at 59.69 189.23 0)
		(effects
			(font
				(size 1.27 1.27)
			)
			(justify left bottom)
		)
	)
	(label "GPIO.24"
		(at 180.34 191.77 180)
		(effects
			(font
				(size 1.27 1.27)
			)
			(justify right bottom)
		)
	)
	(label "GPIO.AIN0"
		(at 180.34 214.63 180)
		(effects
			(font
				(size 1.27 1.27)
			)
			(justify right bottom)
		)
	)
	(label "NFC.IRQ"
		(at 256.54 111.76 0)
		(effects
			(font
				(size 1.27 1.27)
			)
			(justify left bottom)
		)
	)
	(label "GPIO.5/RXD3"
		(at 40.64 214.63 180)
		(effects
			(font
				(size 1.27 1.27)
			)
			(justify right bottom)
		)
	)
	(label "GPIO.1{slash}SCL0"
		(at 59.69 212.09 0)
		(effects
			(font
				(size 1.27 1.27)
			)
			(justify left bottom)
		)
	)
	(label "GPIO.2"
		(at 128.27 168.91 180)
		(effects
			(font
				(size 1.27 1.27)
			)
			(justify right bottom)
		)
	)
	(label "GPIO.20"
		(at 59.69 224.79 0)
		(effects
			(font
				(size 1.27 1.27)
			)
			(justify left bottom)
		)
	)
	(label "GPIO.0{slash}SDA0"
		(at 128.27 210.82 180)
		(effects
			(font
				(size 1.27 1.27)
			)
			(justify right bottom)
		)
	)
	(label "I_{2}C1.SCL"
		(at 246.38 226.06 0)
		(effects
			(font
				(size 1.27 1.27)
			)
			(justify left bottom)
		)
	)
	(label "GPIO.8/TXD4"
		(at 180.34 207.01 180)
		(effects
			(font
				(size 1.27 1.27)
			)
			(justify right bottom)
		)
	)
	(label "GPIO.9/RXD4"
		(at 128.27 205.74 180)
		(effects
			(font
				(size 1.27 1.27)
			)
			(justify right bottom)
		)
	)
	(label "GPIO.26"
		(at 40.64 224.79 180)
		(effects
			(font
				(size 1.27 1.27)
			)
			(justify right bottom)
		)
	)
	(label "GPIO.24"
		(at 59.69 199.39 0)
		(effects
			(font
				(size 1.27 1.27)
			)
			(justify left bottom)
		)
	)
	(label "GPIO.7"
		(at 180.34 209.55 180)
		(effects
			(font
				(size 1.27 1.27)
			)
			(justify right bottom)
		)
	)
	(label "GPIO.10"
		(at 128.27 193.04 180)
		(effects
			(font
				(size 1.27 1.27)
			)
			(justify right bottom)
		)
	)
	(label "GPIO.23"
		(at 180.34 189.23 180)
		(effects
			(font
				(size 1.27 1.27)
			)
			(justify right bottom)
		)
	)
	(label "GPIO.5/RXD3"
		(at 128.27 213.36 180)
		(effects
			(font
				(size 1.27 1.27)
			)
			(justify right bottom)
		)
	)
	(label "GPIO.17"
		(at 40.64 191.77 180)
		(effects
			(font
				(size 1.27 1.27)
			)
			(justify right bottom)
		)
	)
	(label "I_{2}C1.SCL"
		(at 86.36 43.18 0)
		(effects
			(font
				(size 1.27 1.27)
			)
			(justify left bottom)
		)
	)
	(label "GPIO.22"
		(at 128.27 190.5 180)
		(effects
			(font
				(size 1.27 1.27)
			)
			(justify right bottom)
		)
	)
	(label "GPIO.23"
		(at 59.69 196.85 0)
		(effects
			(font
				(size 1.27 1.27)
			)
			(justify left bottom)
		)
	)
	(label "I_{2}C1.SDA"
		(at 86.36 107.95 0)
		(effects
			(font
				(size 1.27 1.27)
			)
			(justify left bottom)
		)
	)
	(label "VLED"
		(at 158.75 106.68 180)
		(effects
			(font
				(size 1.27 1.27)
			)
			(justify right bottom)
		)
	)
	(label "GPIO.13/TXD5"
		(at 128.27 227.33 180)
		(effects
			(font
				(size 1.27 1.27)
			)
			(justify right bottom)
		)
	)
	(label "GPIO.20"
		(at 180.34 231.14 180)
		(effects
			(font
				(size 1.27 1.27)
			)
			(justify right bottom)
		)
	)
	(label "GPIO.AIN0"
		(at 59.69 214.63 0)
		(effects
			(font
				(size 1.27 1.27)
			)
			(justify left bottom)
		)
	)
	(label "GPIO.1{slash}SCL0"
		(at 180.34 212.09 180)
		(effects
			(font
				(size 1.27 1.27)
			)
			(justify right bottom)
		)
	)
	(label "I_{2}C1.SDA"
		(at 246.38 223.52 0)
		(effects
			(font
				(size 1.27 1.27)
			)
			(justify left bottom)
		)
	)
	(label "GPIO.15/TXD0"
		(at 180.34 172.72 180)
		(effects
			(font
				(size 1.27 1.27)
			)
			(justify right bottom)
		)
	)
	(label "GPIO.6"
		(at 128.27 224.79 180)
		(effects
			(font
				(size 1.27 1.27)
			)
			(justify right bottom)
		)
	)
	(label "GPIO.AIN1"
		(at 59.69 194.31 0)
		(effects
			(font
				(size 1.27 1.27)
			)
			(justify left bottom)
		)
	)
	(label "NFC.WKUP_REQ"
		(at 256.54 106.68 0)
		(effects
			(font
				(size 1.27 1.27)
			)
			(justify left bottom)
		)
	)
	(label "GPIO.17"
		(at 128.27 185.42 180)
		(effects
			(font
				(size 1.27 1.27)
			)
			(justify right bottom)
		)
	)
	(label "GPIO.4/TXD3"
		(at 128.27 173.99 180)
		(effects
			(font
				(size 1.27 1.27)
			)
			(justify right bottom)
		)
	)
	(label "GPIO.18"
		(at 59.69 191.77 0)
		(effects
			(font
				(size 1.27 1.27)
			)
			(justify left bottom)
		)
	)
	(label "GPIO.10"
		(at 40.64 201.93 180)
		(effects
			(font
				(size 1.27 1.27)
			)
			(justify right bottom)
		)
	)
	(label "I_{2}C1.SCL"
		(at 162.56 101.6 180)
		(effects
			(font
				(size 1.27 1.27)
			)
			(justify right bottom)
		)
	)
	(label "GPIO.6"
		(at 40.64 217.17 180)
		(effects
			(font
				(size 1.27 1.27)
			)
			(justify right bottom)
		)
	)
	(label "I_{2}C1.SDA"
		(at 162.56 104.14 180)
		(effects
			(font
				(size 1.27 1.27)
			)
			(justify right bottom)
		)
	)
	(label "GPIO.2"
		(at 40.64 181.61 180)
		(effects
			(font
				(size 1.27 1.27)
			)
			(justify right bottom)
		)
	)
	(label "GPIO.4/TXD3"
		(at 40.64 186.69 180)
		(effects
			(font
				(size 1.27 1.27)
			)
			(justify right bottom)
		)
	)
	(label "GPIO.AIN1"
		(at 180.34 186.69 180)
		(effects
			(font
				(size 1.27 1.27)
			)
			(justify right bottom)
		)
	)
	(label "GPIO.27"
		(at 128.27 187.96 180)
		(effects
			(font
				(size 1.27 1.27)
			)
			(justify right bottom)
		)
	)
	(label "GPIO.12/RXD5"
		(at 59.69 217.17 0)
		(effects
			(font
				(size 1.27 1.27)
			)
			(justify left bottom)
		)
	)
	(label "GPIO.3"
		(at 40.64 184.15 180)
		(effects
			(font
				(size 1.27 1.27)
			)
			(justify right bottom)
		)
	)
	(label "GPIO.26"
		(at 128.27 232.41 180)
		(effects
			(font
				(size 1.27 1.27)
			)
			(justify right bottom)
		)
	)
	(label "GPIO.19"
		(at 128.27 229.87 180)
		(effects
			(font
				(size 1.27 1.27)
			)
			(justify right bottom)
		)
	)
	(label "VLED"
		(at 97.79 110.49 0)
		(effects
			(font
				(size 1.27 1.27)
			)
			(justify left bottom)
		)
	)
	(label "NFC.EN"
		(at 256.54 101.6 0)
		(effects
			(font
				(size 1.27 1.27)
			)
			(justify left bottom)
		)
	)
	(label "GPIO.16"
		(at 180.34 228.6 180)
		(effects
			(font
				(size 1.27 1.27)
			)
			(justify right bottom)
		)
	)
	(label "GPIO.9/RXD4"
		(at 40.64 204.47 180)
		(effects
			(font
				(size 1.27 1.27)
			)
			(justify right bottom)
		)
	)
	(label "GPIO.14/RXD0"
		(at 59.69 186.69 0)
		(effects
			(font
				(size 1.27 1.27)
			)
			(justify left bottom)
		)
	)
	(label "GPIO.27"
		(at 40.64 194.31 180)
		(effects
			(font
				(size 1.27 1.27)
			)
			(justify right bottom)
		)
	)
	(label "GPIO.14/RXD0"
		(at 180.34 170.18 180)
		(effects
			(font
				(size 1.27 1.27)
			)
			(justify right bottom)
		)
	)
	(label "GPIO.21"
		(at 180.34 233.68 180)
		(effects
			(font
				(size 1.27 1.27)
			)
			(justify right bottom)
		)
	)
	(label "GPIO.11"
		(at 128.27 208.28 180)
		(effects
			(font
				(size 1.27 1.27)
			)
			(justify right bottom)
		)
	)
	(label "I_{2}C1.SCL"
		(at 86.36 105.41 0)
		(effects
			(font
				(size 1.27 1.27)
			)
			(justify left bottom)
		)
	)
	(label "GPIO.19"
		(at 40.64 222.25 180)
		(effects
			(font
				(size 1.27 1.27)
			)
			(justify right bottom)
		)
	)
	(label "GPIO.25"
		(at 180.34 194.31 180)
		(effects
			(font
				(size 1.27 1.27)
			)
			(justify right bottom)
		)
	)
	(label "GPIO.12/RXD5"
		(at 180.34 226.06 180)
		(effects
			(font
				(size 1.27 1.27)
			)
			(justify right bottom)
		)
	)
	(label "GPIO.3"
		(at 128.27 171.45 180)
		(effects
			(font
				(size 1.27 1.27)
			)
			(justify right bottom)
		)
	)
	(hierarchical_label "I_{2}C1{I_{2}C}"
		(shape bidirectional)
		(at 83.82 101.6 180)
		(effects
			(font
				(size 1.27 1.27)
			)
			(justify right)
		)
	)
	(hierarchical_label "I_{2}C1{I_{2}C}"
		(shape bidirectional)
		(at 165.1 97.79 0)
		(effects
			(font
				(size 1.27 1.27)
			)
			(justify left)
		)
	)
	(hierarchical_label "I_{2}C1{I_{2}C}"
		(shape bidirectional)
		(at 83.82 39.37 180)
		(effects
			(font
				(size 1.27 1.27)
			)
			(justify right)
		)
	)
	(hierarchical_label "GPIO{GPIO}"
		(shape bidirectional)
		(at 163.83 166.37 0)
		(effects
			(font
				(size 1.27 1.27)
			)
			(justify left)
		)
	)
	(hierarchical_label "I_{2}C1{I_{2}C}"
		(shape bidirectional)
		(at 163.83 35.56 0)
		(effects
			(font
				(size 1.27 1.27)
			)
			(justify left)
		)
	)
	(hierarchical_label "GPIO{GPIO}"
		(shape bidirectional)
		(at 78.74 168.91 0)
		(effects
			(font
				(size 1.27 1.27)
			)
			(justify left)
		)
	)
	(hierarchical_label "GPIO{GPIO}"
		(shape bidirectional)
		(at 111.76 165.1 0)
		(effects
			(font
				(size 1.27 1.27)
			)
			(justify left)
		)
	)
	(hierarchical_label "I_{2}C1{I_{2}C}"
		(shape bidirectional)
		(at 266.7 116.84 180)
		(effects
			(font
				(size 1.27 1.27)
			)
			(justify right)
		)
	)
	(hierarchical_label "NFC{NFC}"
		(shape bidirectional)
		(at 255.27 97.79 180)
		(effects
			(font
				(size 1.27 1.27)
			)
			(justify right)
		)
	)
	(symbol
		(lib_id "antmicroWire2BoardConnectors:JST_SH_1x4_SM04B-SRSS-TB-LF-SN")
		(at 109.22 113.03 0)
		(mirror x)
		(unit 1)
		(exclude_from_sim no)
		(in_bom yes)
		(on_board yes)
		(dnp no)
		(fields_autoplaced yes)
		(property "Reference" "J803"
			(at 114.3 93.98 0)
			(effects
				(font
					(size 1.27 1.27)
					(thickness 0.15)
				)
			)
		)
		(property "Value" "JST_SH_1x4_SM04B-SRSS-TB-LF-SN"
			(at 135.89 105.41 0)
			(effects
				(font
					(size 1.27 1.27)
					(thickness 0.15)
				)
				(justify left bottom)
				(hide yes)
			)
		)
		(property "Footprint" "antmicro-footprints:Conn_JST_SH_1x4_SM04B-SRSS-TB-LF-SN"
			(at 135.89 102.87 0)
			(effects
				(font
					(size 1.27 1.27)
					(thickness 0.15)
				)
				(justify left bottom)
				(hide yes)
			)
		)
		(property "Datasheet" "https://www.jst-mfg.com/product/pdf/eng/eSH.pdf"
			(at 135.89 100.33 0)
			(effects
				(font
					(size 1.27 1.27)
					(thickness 0.15)
				)
				(justify left bottom)
				(hide yes)
			)
		)
		(property "Description" ""
			(at 109.22 113.03 0)
			(effects
				(font
					(size 1.27 1.27)
				)
				(hide yes)
			)
		)
		(property "MPN" "SM04B-SRSS-TB(LF)(SN)"
			(at 114.3 96.52 0)
			(effects
				(font
					(size 1.27 1.27)
					(thickness 0.15)
				)
			)
		)
		(property "Manufacturer" "JST Automotive Connectors"
			(at 135.89 97.79 0)
			(effects
				(font
					(size 1.27 1.27)
					(thickness 0.15)
				)
				(justify left bottom)
				(hide yes)
			)
		)
		(property "Author" "Antmicro"
			(at 135.89 95.25 0)
			(effects
				(font
					(size 1.27 1.27)
					(thickness 0.15)
				)
				(justify left bottom)
				(hide yes)
			)
		)
		(property "License" "Apache-2.0"
			(at 135.89 92.71 0)
			(effects
				(font
					(size 1.27 1.27)
					(thickness 0.15)
				)
				(justify left bottom)
				(hide yes)
			)
		)
		(pin "1"
		)
		(pin "2"
		)
		(pin "3"
		)
		(pin "4"
		)
		(pin "MP"
		)
		(instances
			(project "cm4-baseboard"
				(path ""
					(reference "J803")
					(unit 1)
				)
			)
		)
	)
	(symbol
		(lib_id "antmicroCapacitors0402:C_1n_0402")
		(at 309.88 100.33 0)
		(unit 1)
		(exclude_from_sim no)
		(in_bom yes)
		(on_board yes)
		(dnp no)
		(property "Reference" "C812"
			(at 316.23 99.06 0)
			(effects
				(font
					(size 1.27 1.27)
					(thickness 0.15)
				)
			)
		)
		(property "Value" "C_1n_0402"
			(at 330.2 110.49 0)
			(effects
				(font
					(size 1.27 1.27)
					(thickness 0.15)
				)
				(justify left bottom)
				(hide yes)
			)
		)
		(property "Footprint" "antmicro-footprints:C_0402_1005Metric"
			(at 330.2 113.03 0)
			(effects
				(font
					(size 1.27 1.27)
					(thickness 0.15)
				)
				(justify left bottom)
				(hide yes)
			)
		)
		(property "Datasheet" "https://www.murata.com/products/productdetail?partno=GRM1555C1H102JA01%23"
			(at 330.2 115.57 0)
			(effects
				(font
					(size 1.27 1.27)
					(thickness 0.15)
				)
				(justify left bottom)
				(hide yes)
			)
		)
		(property "Description" "SMD Multilayer Ceramic Capacitor, 1000 pF, 50 V, 0402 [1005 Metric], ± 5%, C0G / NP0, GRM Series"
			(at 330.2 133.35 0)
			(effects
				(font
					(size 1.27 1.27)
				)
				(justify left bottom)
				(hide yes)
			)
		)
		(property "MPN" "GRM1555C1H102JA01D"
			(at 330.2 118.11 0)
			(effects
				(font
					(size 1.27 1.27)
					(thickness 0.15)
				)
				(justify left bottom)
				(hide yes)
			)
		)
		(property "Manufacturer" "Murata"
			(at 330.2 120.65 0)
			(effects
				(font
					(size 1.27 1.27)
					(thickness 0.15)
				)
				(justify left bottom)
				(hide yes)
			)
		)
		(property "License" "Apache-2.0"
			(at 330.2 123.19 0)
			(effects
				(font
					(size 1.27 1.27)
					(thickness 0.15)
				)
				(justify left bottom)
				(hide yes)
			)
		)
		(property "Author" "Antmicro"
			(at 330.2 125.73 0)
			(effects
				(font
					(size 1.27 1.27)
					(thickness 0.15)
				)
				(justify left bottom)
				(hide yes)
			)
		)
		(property "Val" "1n"
			(at 316.23 101.6 0)
			(effects
				(font
					(size 1.27 1.27)
					(thickness 0.15)
				)
			)
		)
		(property "Voltage" "50V"
			(at 330.2 128.27 0)
			(effects
				(font
					(size 1.27 1.27)
				)
				(justify left bottom)
				(hide yes)
			)
		)
		(property "Dielectric" "C0G"
			(at 330.2 130.81 0)
			(effects
				(font
					(size 1.27 1.27)
				)
				(justify left bottom)
				(hide yes)
			)
		)
		(pin "1"
		)
		(pin "2"
		)
		(instances
			(project "cm4-baseboard"
				(path ""
					(reference "C812")
					(unit 1)
				)
			)
		)
	)
	(symbol
		(lib_id "antmicropower:GND")
		(at 43.18 228.6 0)
		(unit 1)
		(exclude_from_sim no)
		(in_bom yes)
		(on_board yes)
		(dnp no)
		(property "Reference" "#PWR0802"
			(at 52.07 231.14 0)
			(effects
				(font
					(size 1.27 1.27)
					(thickness 0.15)
				)
				(justify left bottom)
				(hide yes)
			)
		)
		(property "Value" "GND"
			(at 43.18 233.68 0)
			(effects
				(font
					(size 1.27 1.27)
					(thickness 0.15)
				)
			)
		)
		(property "Footprint" ""
			(at 52.07 236.22 0)
			(effects
				(font
					(size 1.27 1.27)
					(thickness 0.15)
				)
				(justify left bottom)
				(hide yes)
			)
		)
		(property "Datasheet" ""
			(at 52.07 241.3 0)
			(effects
				(font
					(size 1.27 1.27)
					(thickness 0.15)
				)
				(justify left bottom)
				(hide yes)
			)
		)
		(property "Description" ""
			(at 43.18 228.6 0)
			(effects
				(font
					(size 1.27 1.27)
				)
				(hide yes)
			)
		)
		(property "Author" "Antmicro"
			(at 52.07 236.22 0)
			(effects
				(font
					(size 1.27 1.27)
					(thickness 0.15)
				)
				(justify left bottom)
				(hide yes)
			)
		)
		(property "License" "Apache-2.0"
			(at 52.07 238.76 0)
			(effects
				(font
					(size 1.27 1.27)
					(thickness 0.15)
				)
				(justify left bottom)
				(hide yes)
			)
		)
		(pin "1"
		)
		(instances
			(project "cm4-baseboard"
				(path ""
					(reference "#PWR0802")
					(unit 1)
				)
			)
		)
	)
	(symbol
		(lib_id "antmicroCapacitors0402:C_36p_0402")
		(at 339.09 123.19 0)
		(unit 1)
		(exclude_from_sim no)
		(in_bom yes)
		(on_board yes)
		(dnp no)
		(property "Reference" "C822"
			(at 341.63 125.73 0)
			(effects
				(font
					(size 1.27 1.27)
					(thickness 0.15)
				)
			)
		)
		(property "Value" "C_36p_0402"
			(at 359.41 133.35 0)
			(effects
				(font
					(size 1.27 1.27)
					(thickness 0.15)
				)
				(justify left bottom)
				(hide yes)
			)
		)
		(property "Footprint" "antmicro-footprints:C_0402_1005Metric"
			(at 359.41 135.89 0)
			(effects
				(font
					(size 1.27 1.27)
					(thickness 0.15)
				)
				(justify left bottom)
				(hide yes)
			)
		)
		(property "Datasheet" "https://eu.mouser.com/datasheet/3/5926/1/C0GNP0_Dielectric.pdf"
			(at 359.41 138.43 0)
			(effects
				(font
					(size 1.27 1.27)
					(thickness 0.15)
				)
				(justify left bottom)
				(hide yes)
			)
		)
		(property "Description" "Multilayer Ceramic Capacitors MLCC, 36 pF, 25V, 0402, C0G, 5%"
			(at 359.41 156.21 0)
			(effects
				(font
					(size 1.27 1.27)
				)
				(justify left bottom)
				(hide yes)
			)
		)
		(property "MPN" "04023A360JAT2A"
			(at 359.41 140.97 0)
			(effects
				(font
					(size 1.27 1.27)
					(thickness 0.15)
				)
				(justify left bottom)
				(hide yes)
			)
		)
		(property "Manufacturer" "KYOCERA AVX"
			(at 359.41 143.51 0)
			(effects
				(font
					(size 1.27 1.27)
					(thickness 0.15)
				)
				(justify left bottom)
				(hide yes)
			)
		)
		(property "License" "Apache-2.0"
			(at 359.41 146.05 0)
			(effects
				(font
					(size 1.27 1.27)
					(thickness 0.15)
				)
				(justify left bottom)
				(hide yes)
			)
		)
		(property "Author" "Antmicro"
			(at 359.41 148.59 0)
			(effects
				(font
					(size 1.27 1.27)
					(thickness 0.15)
				)
				(justify left bottom)
				(hide yes)
			)
		)
		(property "Val" "36pF"
			(at 341.63 127.508 0)
			(effects
				(font
					(size 1.27 1.27)
					(thickness 0.15)
				)
			)
		)
		(property "Voltage" "25 V"
			(at 359.41 151.13 0)
			(effects
				(font
					(size 1.27 1.27)
				)
				(justify left bottom)
				(hide yes)
			)
		)
		(property "Dielectric" "C0G (NP0)"
			(at 359.41 153.67 0)
			(effects
				(font
					(size 1.27 1.27)
				)
				(justify left bottom)
				(hide yes)
			)
		)
		(pin "1"
		)
		(pin "2"
		)
		(instances
			(project "cm4-baseboard"
				(path ""
					(reference "C822")
					(unit 1)
				)
			)
		)
	)
	(symbol
		(lib_id "antmicropower:GND")
		(at 130.81 236.22 0)
		(unit 1)
		(exclude_from_sim no)
		(in_bom yes)
		(on_board yes)
		(dnp no)
		(fields_autoplaced yes)
		(property "Reference" "#PWR0814"
			(at 139.7 238.76 0)
			(effects
				(font
					(size 1.27 1.27)
					(thickness 0.15)
				)
				(justify left bottom)
				(hide yes)
			)
		)
		(property "Value" "GND"
			(at 130.81 241.3 0)
			(effects
				(font
					(size 1.27 1.27)
				)
			)
		)
		(property "Footprint" ""
			(at 139.7 243.84 0)
			(effects
				(font
					(size 1.27 1.27)
					(thickness 0.15)
				)
				(justify left bottom)
				(hide yes)
			)
		)
		(property "Datasheet" ""
			(at 139.7 248.92 0)
			(effects
				(font
					(size 1.27 1.27)
					(thickness 0.15)
				)
				(justify left bottom)
				(hide yes)
			)
		)
		(property "Description" ""
			(at 130.81 236.22 0)
			(effects
				(font
					(size 1.27 1.27)
				)
				(hide yes)
			)
		)
		(property "Author" "Antmicro"
			(at 139.7 243.84 0)
			(effects
				(font
					(size 1.27 1.27)
					(thickness 0.15)
				)
				(justify left bottom)
				(hide yes)
			)
		)
		(property "License" "Apache-2.0"
			(at 139.7 246.38 0)
			(effects
				(font
					(size 1.27 1.27)
					(thickness 0.15)
				)
				(justify left bottom)
				(hide yes)
			)
		)
		(pin "1"
		)
		(instances
			(project "cm4-baseboard"
				(path ""
					(reference "#PWR0814")
					(unit 1)
				)
			)
		)
	)
	(symbol
		(lib_id "antmicropower:GND")
		(at 257.81 63.5 0)
		(unit 1)
		(exclude_from_sim no)
		(in_bom yes)
		(on_board yes)
		(dnp no)
		(property "Reference" "#PWR0829"
			(at 266.7 66.04 0)
			(effects
				(font
					(size 1.27 1.27)
					(thickness 0.15)
				)
				(justify left bottom)
				(hide yes)
			)
		)
		(property "Value" "GND"
			(at 257.81 67.31 0)
			(effects
				(font
					(size 1.27 1.27)
					(thickness 0.15)
				)
			)
		)
		(property "Footprint" ""
			(at 266.7 71.12 0)
			(effects
				(font
					(size 1.27 1.27)
					(thickness 0.15)
				)
				(justify left bottom)
				(hide yes)
			)
		)
		(property "Datasheet" ""
			(at 266.7 76.2 0)
			(effects
				(font
					(size 1.27 1.27)
					(thickness 0.15)
				)
				(justify left bottom)
				(hide yes)
			)
		)
		(property "Description" ""
			(at 257.81 63.5 0)
			(effects
				(font
					(size 1.27 1.27)
				)
				(hide yes)
			)
		)
		(property "Author" "Antmicro"
			(at 266.7 71.12 0)
			(effects
				(font
					(size 1.27 1.27)
					(thickness 0.15)
				)
				(justify left bottom)
				(hide yes)
			)
		)
		(property "License" "Apache-2.0"
			(at 266.7 73.66 0)
			(effects
				(font
					(size 1.27 1.27)
					(thickness 0.15)
				)
				(justify left bottom)
				(hide yes)
			)
		)
		(pin "1"
		)
		(instances
			(project "cm4-baseboard"
				(path ""
					(reference "#PWR0829")
					(unit 1)
				)
			)
		)
	)
	(symbol
		(lib_id "antmicropower:+3V3")
		(at 41.91 177.8 0)
		(unit 1)
		(exclude_from_sim no)
		(in_bom yes)
		(on_board yes)
		(dnp no)
		(property "Reference" "#PWR0801"
			(at 57.15 177.8 0)
			(effects
				(font
					(size 1.27 1.27)
					(thickness 0.15)
				)
				(justify left bottom)
				(hide yes)
			)
		)
		(property "Value" "+3V3"
			(at 41.91 172.72 0)
			(effects
				(font
					(size 1.27 1.27)
					(thickness 0.15)
				)
			)
		)
		(property "Footprint" ""
			(at 57.15 185.42 0)
			(effects
				(font
					(size 1.27 1.27)
					(thickness 0.15)
				)
				(justify left bottom)
				(hide yes)
			)
		)
		(property "Datasheet" ""
			(at 57.15 187.96 0)
			(effects
				(font
					(size 1.27 1.27)
					(thickness 0.15)
				)
				(justify left bottom)
				(hide yes)
			)
		)
		(property "Description" ""
			(at 41.91 177.8 0)
			(effects
				(font
					(size 1.27 1.27)
				)
				(hide yes)
			)
		)
		(property "Author" "Antmicro"
			(at 57.15 180.34 0)
			(effects
				(font
					(size 1.27 1.27)
					(thickness 0.15)
				)
				(justify left bottom)
				(hide yes)
			)
		)
		(property "License" "Apache-2.0"
			(at 57.15 182.88 0)
			(effects
				(font
					(size 1.27 1.27)
					(thickness 0.15)
				)
				(justify left bottom)
				(hide yes)
			)
		)
		(pin "1"
		)
		(instances
			(project "cm4-baseboard"
				(path ""
					(reference "#PWR0801")
					(unit 1)
				)
			)
		)
	)
	(symbol
		(lib_id "antmicropower:GND")
		(at 130.81 196.85 0)
		(unit 1)
		(exclude_from_sim no)
		(in_bom yes)
		(on_board yes)
		(dnp no)
		(fields_autoplaced yes)
		(property "Reference" "#PWR0812"
			(at 139.7 199.39 0)
			(effects
				(font
					(size 1.27 1.27)
					(thickness 0.15)
				)
				(justify left bottom)
				(hide yes)
			)
		)
		(property "Value" "GND"
			(at 130.81 201.93 0)
			(effects
				(font
					(size 1.27 1.27)
				)
			)
		)
		(property "Footprint" ""
			(at 139.7 204.47 0)
			(effects
				(font
					(size 1.27 1.27)
					(thickness 0.15)
				)
				(justify left bottom)
				(hide yes)
			)
		)
		(property "Datasheet" ""
			(at 139.7 209.55 0)
			(effects
				(font
					(size 1.27 1.27)
					(thickness 0.15)
				)
				(justify left bottom)
				(hide yes)
			)
		)
		(property "Description" ""
			(at 130.81 196.85 0)
			(effects
				(font
					(size 1.27 1.27)
				)
				(hide yes)
			)
		)
		(property "Author" "Antmicro"
			(at 139.7 204.47 0)
			(effects
				(font
					(size 1.27 1.27)
					(thickness 0.15)
				)
				(justify left bottom)
				(hide yes)
			)
		)
		(property "License" "Apache-2.0"
			(at 139.7 207.01 0)
			(effects
				(font
					(size 1.27 1.27)
					(thickness 0.15)
				)
				(justify left bottom)
				(hide yes)
			)
		)
		(pin "1"
		)
		(instances
			(project "cm4-baseboard"
				(path ""
					(reference "#PWR0812")
					(unit 1)
				)
			)
		)
	)
	(symbol
		(lib_id "antmicroCapacitors0402:C_12p_0402")
		(at 309.88 92.71 0)
		(unit 1)
		(exclude_from_sim no)
		(in_bom yes)
		(on_board yes)
		(dnp no)
		(property "Reference" "C811"
			(at 316.23 91.44 0)
			(effects
				(font
					(size 1.27 1.27)
					(thickness 0.15)
				)
			)
		)
		(property "Value" "C_12p_0402"
			(at 330.2 102.87 0)
			(effects
				(font
					(size 1.27 1.27)
					(thickness 0.15)
				)
				(justify left bottom)
				(hide yes)
			)
		)
		(property "Footprint" "antmicro-footprints:C_0402_1005Metric"
			(at 330.2 105.41 0)
			(effects
				(font
					(size 1.27 1.27)
					(thickness 0.15)
				)
				(justify left bottom)
				(hide yes)
			)
		)
		(property "Datasheet" "https://product.tdk.com/en/search/capacitor/ceramic/mlcc/info?part_no=CGA2B2C0G1H120J050BA"
			(at 330.2 107.95 0)
			(effects
				(font
					(size 1.27 1.27)
					(thickness 0.15)
				)
				(justify left bottom)
				(hide yes)
			)
		)
		(property "Description" "SMD Multilayer Ceramic Capacitor, 12 pF, 50 V, 0402 [1005 Metric], ± 5%, C0G / NP0, CGA"
			(at 330.2 125.73 0)
			(effects
				(font
					(size 1.27 1.27)
				)
				(justify left bottom)
				(hide yes)
			)
		)
		(property "MPN" "CGA2B2C0G1H120J050BA"
			(at 330.2 110.49 0)
			(effects
				(font
					(size 1.27 1.27)
					(thickness 0.15)
				)
				(justify left bottom)
				(hide yes)
			)
		)
		(property "Manufacturer" "TDK"
			(at 330.2 113.03 0)
			(effects
				(font
					(size 1.27 1.27)
					(thickness 0.15)
				)
				(justify left bottom)
				(hide yes)
			)
		)
		(property "License" "Apache-2.0"
			(at 330.2 115.57 0)
			(effects
				(font
					(size 1.27 1.27)
					(thickness 0.15)
				)
				(justify left bottom)
				(hide yes)
			)
		)
		(property "Author" "Antmicro"
			(at 330.2 118.11 0)
			(effects
				(font
					(size 1.27 1.27)
					(thickness 0.15)
				)
				(justify left bottom)
				(hide yes)
			)
		)
		(property "Val" "12p"
			(at 316.23 93.98 0)
			(effects
				(font
					(size 1.27 1.27)
					(thickness 0.15)
				)
			)
		)
		(property "Voltage" ""
			(at 330.2 120.65 0)
			(effects
				(font
					(size 1.27 1.27)
				)
				(justify left bottom)
				(hide yes)
			)
		)
		(property "Dielectric" ""
			(at 330.2 123.19 0)
			(effects
				(font
					(size 1.27 1.27)
				)
				(justify left bottom)
				(hide yes)
			)
		)
		(pin "2"
		)
		(pin "1"
		)
		(instances
			(project "cm4-baseboard"
				(path ""
					(reference "C811")
					(unit 1)
				)
			)
		)
	)
	(symbol
		(lib_id "antmicroRFTransceiverICs:PN7160A1_VFQFN")
		(at 276.86 92.71 0)
		(unit 1)
		(exclude_from_sim no)
		(in_bom yes)
		(on_board yes)
		(dnp no)
		(fields_autoplaced yes)
		(property "Reference" "U801"
			(at 292.1 85.09 0)
			(effects
				(font
					(size 1.27 1.27)
					(thickness 0.15)
				)
			)
		)
		(property "Value" "PN7160A1_VFQFN"
			(at 321.31 97.79 0)
			(effects
				(font
					(size 1.27 1.27)
					(thickness 0.15)
				)
				(justify left bottom)
				(hide yes)
			)
		)
		(property "Footprint" "antmicro-footprints:VFQFN-40-1EP_6x6mm"
			(at 321.31 100.33 0)
			(effects
				(font
					(size 1.27 1.27)
					(thickness 0.15)
				)
				(justify left bottom)
				(hide yes)
			)
		)
		(property "Datasheet" "https://www.nxp.com/docs/en/data-sheet/PN7160_PN7161.pdf"
			(at 321.31 102.87 0)
			(effects
				(font
					(size 1.27 1.27)
					(thickness 0.15)
				)
				(justify left bottom)
				(hide yes)
			)
		)
		(property "Description" ""
			(at 276.86 92.71 0)
			(effects
				(font
					(size 1.27 1.27)
				)
				(hide yes)
			)
		)
		(property "MPN" "PN7160A1HN/C100E"
			(at 292.1 87.63 0)
			(effects
				(font
					(size 1.27 1.27)
					(thickness 0.15)
				)
			)
		)
		(property "Manufacturer" "NXP"
			(at 321.31 105.41 0)
			(effects
				(font
					(size 1.27 1.27)
					(thickness 0.15)
				)
				(justify left bottom)
				(hide yes)
			)
		)
		(property "Author" "Antmicro"
			(at 321.31 107.95 0)
			(effects
				(font
					(size 1.27 1.27)
					(thickness 0.15)
				)
				(justify left bottom)
				(hide yes)
			)
		)
		(property "License" "Apache-2.0"
			(at 321.31 110.49 0)
			(effects
				(font
					(size 1.27 1.27)
					(thickness 0.15)
				)
				(justify left bottom)
				(hide yes)
			)
		)
		(pin "1"
		)
		(pin "10"
		)
		(pin "11"
		)
		(pin "12"
		)
		(pin "13"
		)
		(pin "14"
		)
		(pin "15"
		)
		(pin "16"
		)
		(pin "17"
		)
		(pin "18"
		)
		(pin "19"
		)
		(pin "2"
		)
		(pin "20"
		)
		(pin "21"
		)
		(pin "22"
		)
		(pin "23"
		)
		(pin "24"
		)
		(pin "25"
		)
		(pin "26"
		)
		(pin "27"
		)
		(pin "28"
		)
		(pin "29"
		)
		(pin "3"
		)
		(pin "30"
		)
		(pin "31"
		)
		(pin "32"
		)
		(pin "33"
		)
		(pin "34"
		)
		(pin "35"
		)
		(pin "36"
		)
		(pin "37"
		)
		(pin "38"
		)
		(pin "39"
		)
		(pin "4"
		)
		(pin "40"
		)
		(pin "41"
		)
		(pin "5"
		)
		(pin "6"
		)
		(pin "7"
		)
		(pin "8"
		)
		(pin "9"
		)
		(instances
			(project "cm4-baseboard"
				(path ""
					(reference "U801")
					(unit 1)
				)
			)
		)
	)
	(symbol
		(lib_id "antmicroCapacitors0402:C_2u2_0402")
		(at 273.05 140.97 180)
		(unit 1)
		(exclude_from_sim no)
		(in_bom yes)
		(on_board yes)
		(dnp no)
		(property "Reference" "C807"
			(at 266.7 139.7 0)
			(effects
				(font
					(size 1.27 1.27)
					(thickness 0.15)
				)
			)
		)
		(property "Value" "C_2u2_0402"
			(at 252.73 130.81 0)
			(effects
				(font
					(size 1.27 1.27)
					(thickness 0.15)
				)
				(justify left bottom)
				(hide yes)
			)
		)
		(property "Footprint" "antmicro-footprints:C_0402_1005Metric"
			(at 252.73 128.27 0)
			(effects
				(font
					(size 1.27 1.27)
					(thickness 0.15)
				)
				(justify left bottom)
				(hide yes)
			)
		)
		(property "Datasheet" "https://product.tdk.com/en/search/capacitor/ceramic/mlcc/info?part_no=C1005X5R1A225K050BC"
			(at 252.73 125.73 0)
			(effects
				(font
					(size 1.27 1.27)
					(thickness 0.15)
				)
				(justify left bottom)
				(hide yes)
			)
		)
		(property "Description" ""
			(at 273.05 140.97 0)
			(effects
				(font
					(size 1.27 1.27)
				)
				(hide yes)
			)
		)
		(property "MPN" "C1005X5R1A225K050BC"
			(at 252.73 123.19 0)
			(effects
				(font
					(size 1.27 1.27)
					(thickness 0.15)
				)
				(justify left bottom)
				(hide yes)
			)
		)
		(property "Manufacturer" "TDK"
			(at 252.73 120.65 0)
			(effects
				(font
					(size 1.27 1.27)
					(thickness 0.15)
				)
				(justify left bottom)
				(hide yes)
			)
		)
		(property "License" "Apache-2.0"
			(at 252.73 118.11 0)
			(effects
				(font
					(size 1.27 1.27)
					(thickness 0.15)
				)
				(justify left bottom)
				(hide yes)
			)
		)
		(property "Author" "Antmicro"
			(at 252.73 115.57 0)
			(effects
				(font
					(size 1.27 1.27)
					(thickness 0.15)
				)
				(justify left bottom)
				(hide yes)
			)
		)
		(property "Val" "2u2"
			(at 273.05 139.7 0)
			(effects
				(font
					(size 1.27 1.27)
					(thickness 0.15)
				)
			)
		)
		(property "Voltage" ""
			(at 252.73 113.03 0)
			(effects
				(font
					(size 1.27 1.27)
				)
				(justify left bottom)
				(hide yes)
			)
		)
		(property "Dielectric" ""
			(at 252.73 110.49 0)
			(effects
				(font
					(size 1.27 1.27)
				)
				(justify left bottom)
				(hide yes)
			)
		)
		(pin "1"
		)
		(pin "2"
		)
		(instances
			(project "cm4-baseboard"
				(path ""
					(reference "C807")
					(unit 1)
				)
			)
		)
	)
	(symbol
		(lib_id "antmicropower:+3V3")
		(at 96.52 90.17 0)
		(unit 1)
		(exclude_from_sim no)
		(in_bom yes)
		(on_board yes)
		(dnp no)
		(property "Reference" "#PWR0806"
			(at 111.76 92.71 0)
			(effects
				(font
					(size 1.27 1.27)
					(thickness 0.15)
				)
				(justify left bottom)
				(hide yes)
			)
		)
		(property "Value" "+3V3"
			(at 96.52 85.09 0)
			(effects
				(font
					(size 1.27 1.27)
					(thickness 0.15)
				)
			)
		)
		(property "Footprint" ""
			(at 111.76 97.79 0)
			(effects
				(font
					(size 1.27 1.27)
					(thickness 0.15)
				)
				(justify left bottom)
				(hide yes)
			)
		)
		(property "Datasheet" ""
			(at 111.76 100.33 0)
			(effects
				(font
					(size 1.27 1.27)
					(thickness 0.15)
				)
				(justify left bottom)
				(hide yes)
			)
		)
		(property "Description" ""
			(at 96.52 90.17 0)
			(effects
				(font
					(size 1.27 1.27)
				)
				(hide yes)
			)
		)
		(property "Author" "Antmicro"
			(at 111.76 97.79 0)
			(effects
				(font
					(size 1.27 1.27)
					(thickness 0.15)
				)
				(justify left bottom)
				(hide yes)
			)
		)
		(property "License" "Apache-2.0"
			(at 111.76 100.33 0)
			(effects
				(font
					(size 1.27 1.27)
					(thickness 0.15)
				)
				(justify left bottom)
				(hide yes)
			)
		)
		(pin "1"
		)
		(instances
			(project "cm4-baseboard"
				(path ""
					(reference "#PWR0806")
					(unit 1)
				)
			)
		)
	)
	(symbol
		(lib_id "antmicropower:GND")
		(at 236.22 133.35 0)
		(unit 1)
		(exclude_from_sim no)
		(in_bom yes)
		(on_board yes)
		(dnp no)
		(property "Reference" "#PWR0824"
			(at 245.11 135.89 0)
			(effects
				(font
					(size 1.27 1.27)
					(thickness 0.15)
				)
				(justify left bottom)
				(hide yes)
			)
		)
		(property "Value" "GND"
			(at 236.22 137.16 0)
			(effects
				(font
					(size 1.27 1.27)
					(thickness 0.15)
				)
			)
		)
		(property "Footprint" ""
			(at 245.11 140.97 0)
			(effects
				(font
					(size 1.27 1.27)
					(thickness 0.15)
				)
				(justify left bottom)
				(hide yes)
			)
		)
		(property "Datasheet" ""
			(at 245.11 146.05 0)
			(effects
				(font
					(size 1.27 1.27)
					(thickness 0.15)
				)
				(justify left bottom)
				(hide yes)
			)
		)
		(property "Description" ""
			(at 236.22 133.35 0)
			(effects
				(font
					(size 1.27 1.27)
				)
				(hide yes)
			)
		)
		(property "Author" "Antmicro"
			(at 245.11 140.97 0)
			(effects
				(font
					(size 1.27 1.27)
					(thickness 0.15)
				)
				(justify left bottom)
				(hide yes)
			)
		)
		(property "License" "Apache-2.0"
			(at 245.11 143.51 0)
			(effects
				(font
					(size 1.27 1.27)
					(thickness 0.15)
				)
				(justify left bottom)
				(hide yes)
			)
		)
		(pin "1"
		)
		(instances
			(project "cm4-baseboard"
				(path ""
					(reference "#PWR0824")
					(unit 1)
				)
			)
		)
	)
	(symbol
		(lib_id "antmicroCapacitors0402:C_template_name_0402")
		(at 344.17 100.33 180)
		(unit 1)
		(exclude_from_sim no)
		(in_bom no)
		(on_board yes)
		(dnp yes)
		(property "Reference" "C820"
			(at 341.6236 97.79 0)
			(effects
				(font
					(size 1.27 1.27)
					(thickness 0.15)
				)
			)
		)
		(property "Value" "C_template_name_0402"
			(at 323.85 90.17 0)
			(effects
				(font
					(size 1.27 1.27)
					(thickness 0.15)
				)
				(justify left bottom)
				(hide yes)
			)
		)
		(property "Footprint" "antmicro-footprints:C_0402_1005Metric"
			(at 323.85 87.63 0)
			(effects
				(font
					(size 1.27 1.27)
					(thickness 0.15)
				)
				(justify left bottom)
				(hide yes)
			)
		)
		(property "Datasheet" "template_datasheet"
			(at 323.85 85.09 0)
			(effects
				(font
					(size 1.27 1.27)
					(thickness 0.15)
				)
				(justify left bottom)
				(hide yes)
			)
		)
		(property "Description" ""
			(at 344.17 100.33 0)
			(effects
				(font
					(size 1.27 1.27)
				)
				(hide yes)
			)
		)
		(property "MPN" "template_MPN"
			(at 323.85 82.55 0)
			(effects
				(font
					(size 1.27 1.27)
					(thickness 0.15)
				)
				(justify left bottom)
				(hide yes)
			)
		)
		(property "Manufacturer" "template_manufacturer"
			(at 323.85 80.01 0)
			(effects
				(font
					(size 1.27 1.27)
					(thickness 0.15)
				)
				(justify left bottom)
				(hide yes)
			)
		)
		(property "License" "Apache-2.0"
			(at 323.85 77.47 0)
			(effects
				(font
					(size 1.27 1.27)
					(thickness 0.15)
				)
				(justify left bottom)
				(hide yes)
			)
		)
		(property "Author" "Antmicro"
			(at 323.85 74.93 0)
			(effects
				(font
					(size 1.27 1.27)
					(thickness 0.15)
				)
				(justify left bottom)
				(hide yes)
			)
		)
		(property "Val" "template_value"
			(at 341.6237 104.14 0)
			(effects
				(font
					(size 1.27 1.27)
					(thickness 0.15)
				)
				(hide yes)
			)
		)
		(property "Voltage" "template_voltage"
			(at 323.85 72.39 0)
			(effects
				(font
					(size 1.27 1.27)
				)
				(justify left bottom)
				(hide yes)
			)
		)
		(property "Dielectric" "template_dielectric"
			(at 323.85 69.85 0)
			(effects
				(font
					(size 1.27 1.27)
				)
				(justify left bottom)
				(hide yes)
			)
		)
		(pin "1"
		)
		(pin "2"
		)
		(instances
			(project "cm4-baseboard"
				(path ""
					(reference "C820")
					(unit 1)
				)
			)
		)
	)
	(symbol
		(lib_id "antmicroResistors0402:R_10k_0402")
		(at 236.22 120.65 90)
		(unit 1)
		(exclude_from_sim no)
		(in_bom no)
		(on_board yes)
		(dnp yes)
		(property "Reference" "R803"
			(at 237.49 116.84 90)
			(effects
				(font
					(size 1.27 1.27)
					(thickness 0.15)
				)
				(justify right)
			)
		)
		(property "Value" "R_10k_0402"
			(at 248.92 100.33 0)
			(effects
				(font
					(size 1.27 1.27)
					(thickness 0.15)
				)
				(justify left bottom)
				(hide yes)
			)
		)
		(property "Footprint" "antmicro-footprints:R_0402_1005Metric"
			(at 251.46 100.33 0)
			(effects
				(font
					(size 1.27 1.27)
					(thickness 0.15)
				)
				(justify left bottom)
				(hide yes)
			)
		)
		(property "Datasheet" "https://www.bourns.com/docs/product-datasheets/cr.pdf"
			(at 254 100.33 0)
			(effects
				(font
					(size 1.27 1.27)
					(thickness 0.15)
				)
				(justify left bottom)
				(hide yes)
			)
		)
		(property "Description" ""
			(at 236.22 120.65 0)
			(effects
				(font
					(size 1.27 1.27)
				)
				(hide yes)
			)
		)
		(property "MPN" "CR0402-FX-1002GLF"
			(at 256.54 100.33 0)
			(effects
				(font
					(size 1.27 1.27)
					(thickness 0.15)
				)
				(justify left bottom)
				(hide yes)
			)
		)
		(property "Manufacturer" "Bourns"
			(at 259.08 100.33 0)
			(effects
				(font
					(size 1.27 1.27)
					(thickness 0.15)
				)
				(justify left bottom)
				(hide yes)
			)
		)
		(property "License" "Apache-2.0"
			(at 261.62 100.33 0)
			(effects
				(font
					(size 1.27 1.27)
					(thickness 0.15)
				)
				(justify left bottom)
				(hide yes)
			)
		)
		(property "Author" "Antmicro"
			(at 264.16 100.33 0)
			(effects
				(font
					(size 1.27 1.27)
					(thickness 0.15)
				)
				(justify left bottom)
				(hide yes)
			)
		)
		(property "Val" "10k"
			(at 237.49 119.38 90)
			(effects
				(font
					(size 1.27 1.27)
					(thickness 0.15)
				)
				(justify right)
			)
		)
		(property "Tolerance" "1%"
			(at 246.38 100.33 0)
			(effects
				(font
					(size 1.27 1.27)
				)
				(justify left bottom)
				(hide yes)
			)
		)
		(pin "1"
		)
		(pin "2"
		)
		(instances
			(project "cm4-baseboard"
				(path ""
					(reference "R803")
					(unit 1)
				)
			)
		)
	)
	(symbol
		(lib_id "antmicroCapacitors0402:C_2u2_0402")
		(at 273.05 146.05 180)
		(unit 1)
		(exclude_from_sim no)
		(in_bom yes)
		(on_board yes)
		(dnp no)
		(property "Reference" "C808"
			(at 266.7 144.78 0)
			(effects
				(font
					(size 1.27 1.27)
					(thickness 0.15)
				)
			)
		)
		(property "Value" "C_2u2_0402"
			(at 252.73 135.89 0)
			(effects
				(font
					(size 1.27 1.27)
					(thickness 0.15)
				)
				(justify left bottom)
				(hide yes)
			)
		)
		(property "Footprint" "antmicro-footprints:C_0402_1005Metric"
			(at 252.73 133.35 0)
			(effects
				(font
					(size 1.27 1.27)
					(thickness 0.15)
				)
				(justify left bottom)
				(hide yes)
			)
		)
		(property "Datasheet" "https://product.tdk.com/en/search/capacitor/ceramic/mlcc/info?part_no=C1005X5R1A225K050BC"
			(at 252.73 130.81 0)
			(effects
				(font
					(size 1.27 1.27)
					(thickness 0.15)
				)
				(justify left bottom)
				(hide yes)
			)
		)
		(property "Description" ""
			(at 273.05 146.05 0)
			(effects
				(font
					(size 1.27 1.27)
				)
				(hide yes)
			)
		)
		(property "MPN" "C1005X5R1A225K050BC"
			(at 252.73 128.27 0)
			(effects
				(font
					(size 1.27 1.27)
					(thickness 0.15)
				)
				(justify left bottom)
				(hide yes)
			)
		)
		(property "Manufacturer" "TDK"
			(at 252.73 125.73 0)
			(effects
				(font
					(size 1.27 1.27)
					(thickness 0.15)
				)
				(justify left bottom)
				(hide yes)
			)
		)
		(property "License" "Apache-2.0"
			(at 252.73 123.19 0)
			(effects
				(font
					(size 1.27 1.27)
					(thickness 0.15)
				)
				(justify left bottom)
				(hide yes)
			)
		)
		(property "Author" "Antmicro"
			(at 252.73 120.65 0)
			(effects
				(font
					(size 1.27 1.27)
					(thickness 0.15)
				)
				(justify left bottom)
				(hide yes)
			)
		)
		(property "Val" "2u2"
			(at 273.05 144.78 0)
			(effects
				(font
					(size 1.27 1.27)
					(thickness 0.15)
				)
			)
		)
		(property "Voltage" ""
			(at 252.73 118.11 0)
			(effects
				(font
					(size 1.27 1.27)
				)
				(justify left bottom)
				(hide yes)
			)
		)
		(property "Dielectric" ""
			(at 252.73 115.57 0)
			(effects
				(font
					(size 1.27 1.27)
				)
				(justify left bottom)
				(hide yes)
			)
		)
		(pin "1"
		)
		(pin "2"
		)
		(instances
			(project "cm4-baseboard"
				(path ""
					(reference "C808")
					(unit 1)
				)
			)
		)
	)
	(symbol
		(lib_id "antmicropower:GND")
		(at 130.81 177.8 0)
		(unit 1)
		(exclude_from_sim no)
		(in_bom yes)
		(on_board yes)
		(dnp no)
		(fields_autoplaced yes)
		(property "Reference" "#PWR0811"
			(at 139.7 180.34 0)
			(effects
				(font
					(size 1.27 1.27)
					(thickness 0.15)
				)
				(justify left bottom)
				(hide yes)
			)
		)
		(property "Value" "GND"
			(at 130.81 182.88 0)
			(effects
				(font
					(size 1.27 1.27)
				)
			)
		)
		(property "Footprint" ""
			(at 139.7 185.42 0)
			(effects
				(font
					(size 1.27 1.27)
					(thickness 0.15)
				)
				(justify left bottom)
				(hide yes)
			)
		)
		(property "Datasheet" ""
			(at 139.7 190.5 0)
			(effects
				(font
					(size 1.27 1.27)
					(thickness 0.15)
				)
				(justify left bottom)
				(hide yes)
			)
		)
		(property "Description" ""
			(at 130.81 177.8 0)
			(effects
				(font
					(size 1.27 1.27)
				)
				(hide yes)
			)
		)
		(property "Author" "Antmicro"
			(at 139.7 185.42 0)
			(effects
				(font
					(size 1.27 1.27)
					(thickness 0.15)
				)
				(justify left bottom)
				(hide yes)
			)
		)
		(property "License" "Apache-2.0"
			(at 139.7 187.96 0)
			(effects
				(font
					(size 1.27 1.27)
					(thickness 0.15)
				)
				(justify left bottom)
				(hide yes)
			)
		)
		(pin "1"
		)
		(instances
			(project "cm4-baseboard"
				(path ""
					(reference "#PWR0811")
					(unit 1)
				)
			)
		)
	)
	(symbol
		(lib_id "antmicroTestPoints:TP_0.75mm_SMD")
		(at 275.59 114.3 180)
		(unit 1)
		(exclude_from_sim no)
		(in_bom no)
		(on_board yes)
		(dnp no)
		(property "Reference" "TP803"
			(at 271.78 114.3 0)
			(effects
				(font
					(size 1.27 1.27)
					(thickness 0.15)
				)
				(justify left)
			)
		)
		(property "Value" "TP_0.75mm_SMD"
			(at 260.35 106.68 0)
			(effects
				(font
					(size 1.27 1.27)
					(thickness 0.15)
				)
				(justify left bottom)
				(hide yes)
			)
		)
		(property "Footprint" "antmicro-footprints:TP_SMD_0.75mm"
			(at 264.795 107.95 0)
			(effects
				(font
					(size 1.27 1.27)
					(thickness 0.15)
				)
				(justify left bottom)
				(hide yes)
			)
		)
		(property "Datasheet" ""
			(at 257.81 101.6 0)
			(effects
				(font
					(size 1.27 1.27)
					(thickness 0.15)
				)
				(justify left bottom)
				(hide yes)
			)
		)
		(property "Description" ""
			(at 275.59 114.3 0)
			(effects
				(font
					(size 1.27 1.27)
				)
				(hide yes)
			)
		)
		(property "Author" "Antmicro"
			(at 264.795 105.41 0)
			(effects
				(font
					(size 1.27 1.27)
					(thickness 0.15)
				)
				(justify left bottom)
				(hide yes)
			)
		)
		(property "License" "Apache-2.0"
			(at 264.795 102.87 0)
			(effects
				(font
					(size 1.27 1.27)
					(thickness 0.15)
				)
				(justify left bottom)
				(hide yes)
			)
		)
		(property "MPN" ""
			(at 264.795 102.87 0)
			(effects
				(font
					(size 1.27 1.27)
					(thickness 0.15)
				)
				(justify left bottom)
				(hide yes)
			)
		)
		(property "Manufacturer" ""
			(at 264.795 107.95 0)
			(effects
				(font
					(size 1.27 1.27)
					(thickness 0.15)
				)
				(justify left bottom)
				(hide yes)
			)
		)
		(pin "1"
		)
		(instances
			(project "cm4-baseboard"
				(path ""
					(reference "TP803")
					(unit 1)
				)
			)
		)
	)
	(symbol
		(lib_id "antmicroCapacitors0402:C_template_name_0402")
		(at 322.58 121.92 90)
		(unit 1)
		(exclude_from_sim no)
		(in_bom no)
		(on_board yes)
		(dnp yes)
		(property "Reference" "C817"
			(at 323.85 118.1036 90)
			(effects
				(font
					(size 1.27 1.27)
					(thickness 0.15)
				)
				(justify right)
			)
		)
		(property "Value" "C_template_name_0402"
			(at 332.74 101.6 0)
			(effects
				(font
					(size 1.27 1.27)
					(thickness 0.15)
				)
				(justify left bottom)
				(hide yes)
			)
		)
		(property "Footprint" "antmicro-footprints:C_0402_1005Metric"
			(at 335.28 101.6 0)
			(effects
				(font
					(size 1.27 1.27)
					(thickness 0.15)
				)
				(justify left bottom)
				(hide yes)
			)
		)
		(property "Datasheet" "template_datasheet"
			(at 337.82 101.6 0)
			(effects
				(font
					(size 1.27 1.27)
					(thickness 0.15)
				)
				(justify left bottom)
				(hide yes)
			)
		)
		(property "Description" ""
			(at 322.58 121.92 0)
			(effects
				(font
					(size 1.27 1.27)
				)
				(hide yes)
			)
		)
		(property "MPN" "template_MPN"
			(at 340.36 101.6 0)
			(effects
				(font
					(size 1.27 1.27)
					(thickness 0.15)
				)
				(justify left bottom)
				(hide yes)
			)
		)
		(property "Manufacturer" "template_manufacturer"
			(at 342.9 101.6 0)
			(effects
				(font
					(size 1.27 1.27)
					(thickness 0.15)
				)
				(justify left bottom)
				(hide yes)
			)
		)
		(property "License" "Apache-2.0"
			(at 345.44 101.6 0)
			(effects
				(font
					(size 1.27 1.27)
					(thickness 0.15)
				)
				(justify left bottom)
				(hide yes)
			)
		)
		(property "Author" "Antmicro"
			(at 347.98 101.6 0)
			(effects
				(font
					(size 1.27 1.27)
					(thickness 0.15)
				)
				(justify left bottom)
				(hide yes)
			)
		)
		(property "Val" "template_value"
			(at 318.77 119.3737 0)
			(effects
				(font
					(size 1.27 1.27)
					(thickness 0.15)
				)
				(hide yes)
			)
		)
		(property "Voltage" "template_voltage"
			(at 350.52 101.6 0)
			(effects
				(font
					(size 1.27 1.27)
				)
				(justify left bottom)
				(hide yes)
			)
		)
		(property "Dielectric" "template_dielectric"
			(at 353.06 101.6 0)
			(effects
				(font
					(size 1.27 1.27)
				)
				(justify left bottom)
				(hide yes)
			)
		)
		(pin "1"
		)
		(pin "2"
		)
		(instances
			(project "cm4-baseboard"
				(path ""
					(reference "C817")
					(unit 1)
				)
			)
		)
	)
	(symbol
		(lib_id "antmicroTVSDiodes:PUSB3F96X_PASS")
		(at 132.08 205.74 0)
		(unit 1)
		(exclude_from_sim no)
		(in_bom yes)
		(on_board yes)
		(dnp no)
		(fields_autoplaced yes)
		(property "Reference" "D803"
			(at 146.05 208.2799 0)
			(effects
				(font
					(size 1.27 1.27)
					(thickness 0.15)
				)
				(justify left)
			)
		)
		(property "Value" "PUSB3F96X_PASS"
			(at 157.48 213.36 0)
			(effects
				(font
					(size 1.27 1.27)
					(thickness 0.15)
				)
				(justify left bottom)
				(hide yes)
			)
		)
		(property "Footprint" "antmicro-footprints:Nexperia_DFN-10_2.5x1mm_P0.5mm"
			(at 157.48 215.9 0)
			(effects
				(font
					(size 1.27 1.27)
					(thickness 0.15)
				)
				(justify left bottom)
				(hide yes)
			)
		)
		(property "Datasheet" "https://mouser.com/datasheet/2/916/PUSB3F96-1600324.pdf"
			(at 157.48 218.44 0)
			(effects
				(font
					(size 1.27 1.27)
					(thickness 0.15)
				)
				(justify left bottom)
				(hide yes)
			)
		)
		(property "Description" ""
			(at 132.08 205.74 0)
			(effects
				(font
					(size 1.27 1.27)
				)
				(hide yes)
			)
		)
		(property "Manufacturer" "Nexperia"
			(at 157.48 220.98 0)
			(effects
				(font
					(size 1.27 1.27)
					(thickness 0.15)
				)
				(justify left bottom)
				(hide yes)
			)
		)
		(property "MPN" "PUSB3F96X"
			(at 146.05 210.8199 0)
			(effects
				(font
					(size 1.27 1.27)
					(thickness 0.15)
				)
				(justify left)
			)
		)
		(property "Author" "Antmicro"
			(at 157.48 223.52 0)
			(effects
				(font
					(size 1.27 1.27)
					(thickness 0.15)
				)
				(justify left bottom)
				(hide yes)
			)
		)
		(property "License" "Apache-2.0"
			(at 157.48 226.06 0)
			(effects
				(font
					(size 1.27 1.27)
					(thickness 0.15)
				)
				(justify left bottom)
				(hide yes)
			)
		)
		(pin "1"
		)
		(pin "10"
		)
		(pin "2"
		)
		(pin "3"
		)
		(pin "4"
		)
		(pin "5"
		)
		(pin "6"
		)
		(pin "7"
		)
		(pin "8"
		)
		(pin "9"
		)
		(instances
			(project "cm4-baseboard"
				(path ""
					(reference "D803")
					(unit 1)
				)
			)
		)
	)
	(symbol
		(lib_id "antmicropower:GND")
		(at 264.16 157.48 0)
		(unit 1)
		(exclude_from_sim no)
		(in_bom yes)
		(on_board yes)
		(dnp no)
		(property "Reference" "#PWR0832"
			(at 273.05 160.02 0)
			(effects
				(font
					(size 1.27 1.27)
					(thickness 0.15)
				)
				(justify left bottom)
				(hide yes)
			)
		)
		(property "Value" "GND"
			(at 264.16 161.29 0)
			(effects
				(font
					(size 1.27 1.27)
					(thickness 0.15)
				)
			)
		)
		(property "Footprint" ""
			(at 273.05 165.1 0)
			(effects
				(font
					(size 1.27 1.27)
					(thickness 0.15)
				)
				(justify left bottom)
				(hide yes)
			)
		)
		(property "Datasheet" ""
			(at 273.05 170.18 0)
			(effects
				(font
					(size 1.27 1.27)
					(thickness 0.15)
				)
				(justify left bottom)
				(hide yes)
			)
		)
		(property "Description" ""
			(at 264.16 157.48 0)
			(effects
				(font
					(size 1.27 1.27)
				)
				(hide yes)
			)
		)
		(property "Author" "Antmicro"
			(at 273.05 165.1 0)
			(effects
				(font
					(size 1.27 1.27)
					(thickness 0.15)
				)
				(justify left bottom)
				(hide yes)
			)
		)
		(property "License" "Apache-2.0"
			(at 273.05 167.64 0)
			(effects
				(font
					(size 1.27 1.27)
					(thickness 0.15)
				)
				(justify left bottom)
				(hide yes)
			)
		)
		(pin "1"
		)
		(instances
			(project "cm4-baseboard"
				(path ""
					(reference "#PWR0832")
					(unit 1)
				)
			)
		)
	)
	(symbol
		(lib_id "antmicropower:+5V")
		(at 91.44 90.17 0)
		(mirror y)
		(unit 1)
		(exclude_from_sim no)
		(in_bom yes)
		(on_board yes)
		(dnp no)
		(property "Reference" "#PWR0805"
			(at 76.2 92.71 0)
			(effects
				(font
					(size 1.27 1.27)
					(thickness 0.15)
				)
				(justify left bottom)
				(hide yes)
			)
		)
		(property "Value" "+5V"
			(at 91.44 85.09 0)
			(effects
				(font
					(size 1.27 1.27)
					(thickness 0.15)
				)
			)
		)
		(property "Footprint" ""
			(at 76.2 97.79 0)
			(effects
				(font
					(size 1.27 1.27)
					(thickness 0.15)
				)
				(justify left bottom)
				(hide yes)
			)
		)
		(property "Datasheet" ""
			(at 76.2 100.33 0)
			(effects
				(font
					(size 1.27 1.27)
					(thickness 0.15)
				)
				(justify left bottom)
				(hide yes)
			)
		)
		(property "Description" ""
			(at 91.44 90.17 0)
			(effects
				(font
					(size 1.27 1.27)
				)
				(hide yes)
			)
		)
		(property "Author" "Antmicro"
			(at 76.2 97.79 0)
			(effects
				(font
					(size 1.27 1.27)
					(thickness 0.15)
				)
				(justify left bottom)
				(hide yes)
			)
		)
		(property "License" "Apache-2.0"
			(at 76.2 100.33 0)
			(effects
				(font
					(size 1.27 1.27)
					(thickness 0.15)
				)
				(justify left bottom)
				(hide yes)
			)
		)
		(pin "1"
		)
		(instances
			(project "cm4-baseboard"
				(path ""
					(reference "#PWR0805")
					(unit 1)
				)
			)
		)
	)
	(symbol
		(lib_id "antmicropower:GND")
		(at 151.13 52.07 0)
		(unit 1)
		(exclude_from_sim no)
		(in_bom yes)
		(on_board yes)
		(dnp no)
		(property "Reference" "#PWR0816"
			(at 160.02 54.61 0)
			(effects
				(font
					(size 1.27 1.27)
					(thickness 0.15)
				)
				(justify left bottom)
				(hide yes)
			)
		)
		(property "Value" "GND"
			(at 151.13 57.15 0)
			(effects
				(font
					(size 1.27 1.27)
					(thickness 0.15)
				)
			)
		)
		(property "Footprint" ""
			(at 160.02 59.69 0)
			(effects
				(font
					(size 1.27 1.27)
					(thickness 0.15)
				)
				(justify left bottom)
				(hide yes)
			)
		)
		(property "Datasheet" ""
			(at 160.02 64.77 0)
			(effects
				(font
					(size 1.27 1.27)
					(thickness 0.15)
				)
				(justify left bottom)
				(hide yes)
			)
		)
		(property "Description" ""
			(at 151.13 52.07 0)
			(effects
				(font
					(size 1.27 1.27)
				)
				(hide yes)
			)
		)
		(property "Author" "Antmicro"
			(at 160.02 59.69 0)
			(effects
				(font
					(size 1.27 1.27)
					(thickness 0.15)
				)
				(justify left bottom)
				(hide yes)
			)
		)
		(property "License" "Apache-2.0"
			(at 160.02 62.23 0)
			(effects
				(font
					(size 1.27 1.27)
					(thickness 0.15)
				)
				(justify left bottom)
				(hide yes)
			)
		)
		(pin "1"
		)
		(instances
			(project "cm4-baseboard"
				(path ""
					(reference "#PWR0816")
					(unit 1)
				)
			)
		)
	)
	(symbol
		(lib_id "antmicroDiodesRectifiersSingle:RB521S30T1G")
		(at 300.99 219.71 90)
		(unit 1)
		(exclude_from_sim no)
		(in_bom yes)
		(on_board yes)
		(dnp no)
		(fields_autoplaced yes)
		(property "Reference" "D811"
			(at 303.53 215.8999 90)
			(effects
				(font
					(size 1.27 1.27)
				)
				(justify right)
			)
		)
		(property "Value" "RB521S30T1G"
			(at 316.23 196.85 0)
			(effects
				(font
					(size 1.27 1.27)
					(thickness 0.15)
				)
				(justify left bottom)
				(hide yes)
			)
		)
		(property "Footprint" "antmicro-footprints:SOD-523"
			(at 311.15 196.85 0)
			(effects
				(font
					(size 1.27 1.27)
					(thickness 0.15)
				)
				(justify left bottom)
				(hide yes)
			)
		)
		(property "Datasheet" "https://www.onsemi.com/pdf/datasheet/rb521s30t1-d.pdf"
			(at 313.69 196.85 0)
			(effects
				(font
					(size 1.27 1.27)
					(thickness 0.15)
				)
				(justify left bottom)
				(hide yes)
			)
		)
		(property "Description" ""
			(at 300.99 219.71 0)
			(effects
				(font
					(size 1.27 1.27)
				)
				(hide yes)
			)
		)
		(property "MPN" "RB521S30T1G"
			(at 303.53 218.44 90)
			(effects
				(font
					(size 1.27 1.27)
					(thickness 0.15)
				)
				(justify right)
			)
		)
		(property "Manufacturer" "ON Semiconductor"
			(at 318.77 196.85 0)
			(effects
				(font
					(size 1.27 1.27)
					(thickness 0.15)
				)
				(justify left bottom)
				(hide yes)
			)
		)
		(property "Author" "Antmicro"
			(at 321.31 196.85 0)
			(effects
				(font
					(size 1.27 1.27)
					(thickness 0.15)
				)
				(justify left bottom)
				(hide yes)
			)
		)
		(property "License" "Apache-2.0"
			(at 323.85 196.85 0)
			(effects
				(font
					(size 1.27 1.27)
					(thickness 0.15)
				)
				(justify left bottom)
				(hide yes)
			)
		)
		(pin "1"
		)
		(pin "2"
		)
		(instances
			(project "cm4-baseboard"
				(path ""
					(reference "D811")
					(unit 1)
				)
			)
		)
	)
	(symbol
		(lib_id "antmicropower:GND")
		(at 317.5 116.84 0)
		(unit 1)
		(exclude_from_sim no)
		(in_bom yes)
		(on_board yes)
		(dnp no)
		(property "Reference" "#PWR0835"
			(at 326.39 119.38 0)
			(effects
				(font
					(size 1.27 1.27)
					(thickness 0.15)
				)
				(justify left bottom)
				(hide yes)
			)
		)
		(property "Value" "GND"
			(at 317.5 120.65 0)
			(effects
				(font
					(size 1.27 1.27)
					(thickness 0.15)
				)
			)
		)
		(property "Footprint" ""
			(at 326.39 124.46 0)
			(effects
				(font
					(size 1.27 1.27)
					(thickness 0.15)
				)
				(justify left bottom)
				(hide yes)
			)
		)
		(property "Datasheet" ""
			(at 326.39 129.54 0)
			(effects
				(font
					(size 1.27 1.27)
					(thickness 0.15)
				)
				(justify left bottom)
				(hide yes)
			)
		)
		(property "Description" ""
			(at 317.5 116.84 0)
			(effects
				(font
					(size 1.27 1.27)
				)
				(hide yes)
			)
		)
		(property "Author" "Antmicro"
			(at 326.39 124.46 0)
			(effects
				(font
					(size 1.27 1.27)
					(thickness 0.15)
				)
				(justify left bottom)
				(hide yes)
			)
		)
		(property "License" "Apache-2.0"
			(at 326.39 127 0)
			(effects
				(font
					(size 1.27 1.27)
					(thickness 0.15)
				)
				(justify left bottom)
				(hide yes)
			)
		)
		(pin "1"
		)
		(instances
			(project "cm4-baseboard"
				(path ""
					(reference "#PWR0835")
					(unit 1)
				)
			)
		)
	)
	(symbol
		(lib_id "antmicroCapacitors0402:C_template_name_0402")
		(at 344.17 130.81 0)
		(mirror y)
		(unit 1)
		(exclude_from_sim no)
		(in_bom no)
		(on_board yes)
		(dnp yes)
		(property "Reference" "C823"
			(at 341.6236 134.62 0)
			(effects
				(font
					(size 1.27 1.27)
					(thickness 0.15)
				)
			)
		)
		(property "Value" "C_template_name_0402"
			(at 323.85 140.97 0)
			(effects
				(font
					(size 1.27 1.27)
					(thickness 0.15)
				)
				(justify left bottom)
				(hide yes)
			)
		)
		(property "Footprint" "antmicro-footprints:C_0402_1005Metric"
			(at 323.85 143.51 0)
			(effects
				(font
					(size 1.27 1.27)
					(thickness 0.15)
				)
				(justify left bottom)
				(hide yes)
			)
		)
		(property "Datasheet" "template_datasheet"
			(at 323.85 146.05 0)
			(effects
				(font
					(size 1.27 1.27)
					(thickness 0.15)
				)
				(justify left bottom)
				(hide yes)
			)
		)
		(property "Description" ""
			(at 344.17 130.81 0)
			(effects
				(font
					(size 1.27 1.27)
				)
				(hide yes)
			)
		)
		(property "MPN" "template_MPN"
			(at 323.85 148.59 0)
			(effects
				(font
					(size 1.27 1.27)
					(thickness 0.15)
				)
				(justify left bottom)
				(hide yes)
			)
		)
		(property "Manufacturer" "template_manufacturer"
			(at 323.85 151.13 0)
			(effects
				(font
					(size 1.27 1.27)
					(thickness 0.15)
				)
				(justify left bottom)
				(hide yes)
			)
		)
		(property "License" "Apache-2.0"
			(at 323.85 153.67 0)
			(effects
				(font
					(size 1.27 1.27)
					(thickness 0.15)
				)
				(justify left bottom)
				(hide yes)
			)
		)
		(property "Author" "Antmicro"
			(at 323.85 156.21 0)
			(effects
				(font
					(size 1.27 1.27)
					(thickness 0.15)
				)
				(justify left bottom)
				(hide yes)
			)
		)
		(property "Val" "template_value"
			(at 341.6237 127 0)
			(effects
				(font
					(size 1.27 1.27)
					(thickness 0.15)
				)
				(hide yes)
			)
		)
		(property "Voltage" "template_voltage"
			(at 323.85 158.75 0)
			(effects
				(font
					(size 1.27 1.27)
				)
				(justify left bottom)
				(hide yes)
			)
		)
		(property "Dielectric" "template_dielectric"
			(at 323.85 161.29 0)
			(effects
				(font
					(size 1.27 1.27)
				)
				(justify left bottom)
				(hide yes)
			)
		)
		(pin "1"
		)
		(pin "2"
		)
		(instances
			(project "cm4-baseboard"
				(path ""
					(reference "C823")
					(unit 1)
				)
			)
		)
	)
	(symbol
		(lib_id "antmicroTestPoints:TP_0.75mm_SMD")
		(at 275.59 104.14 180)
		(unit 1)
		(exclude_from_sim no)
		(in_bom no)
		(on_board yes)
		(dnp no)
		(property "Reference" "TP801"
			(at 271.78 104.14 0)
			(effects
				(font
					(size 1.27 1.27)
					(thickness 0.15)
				)
				(justify left)
			)
		)
		(property "Value" "TP_0.75mm_SMD"
			(at 260.35 96.52 0)
			(effects
				(font
					(size 1.27 1.27)
					(thickness 0.15)
				)
				(justify left bottom)
				(hide yes)
			)
		)
		(property "Footprint" "antmicro-footprints:TP_SMD_0.75mm"
			(at 264.795 97.79 0)
			(effects
				(font
					(size 1.27 1.27)
					(thickness 0.15)
				)
				(justify left bottom)
				(hide yes)
			)
		)
		(property "Datasheet" ""
			(at 257.81 91.44 0)
			(effects
				(font
					(size 1.27 1.27)
					(thickness 0.15)
				)
				(justify left bottom)
				(hide yes)
			)
		)
		(property "Description" ""
			(at 275.59 104.14 0)
			(effects
				(font
					(size 1.27 1.27)
				)
				(hide yes)
			)
		)
		(property "Author" "Antmicro"
			(at 264.795 95.25 0)
			(effects
				(font
					(size 1.27 1.27)
					(thickness 0.15)
				)
				(justify left bottom)
				(hide yes)
			)
		)
		(property "License" "Apache-2.0"
			(at 264.795 92.71 0)
			(effects
				(font
					(size 1.27 1.27)
					(thickness 0.15)
				)
				(justify left bottom)
				(hide yes)
			)
		)
		(property "MPN" ""
			(at 264.795 92.71 0)
			(effects
				(font
					(size 1.27 1.27)
					(thickness 0.15)
				)
				(justify left bottom)
				(hide yes)
			)
		)
		(property "Manufacturer" ""
			(at 264.795 97.79 0)
			(effects
				(font
					(size 1.27 1.27)
					(thickness 0.15)
				)
				(justify left bottom)
				(hide yes)
			)
		)
		(pin "1"
		)
		(instances
			(project "cm4-baseboard"
				(path ""
					(reference "TP801")
					(unit 1)
				)
			)
		)
	)
	(symbol
		(lib_id "antmicroCapacitors0402:C_1u_0402")
		(at 257.81 62.23 90)
		(unit 1)
		(exclude_from_sim no)
		(in_bom yes)
		(on_board yes)
		(dnp no)
		(fields_autoplaced yes)
		(property "Reference" "C802"
			(at 260.35 58.4135 90)
			(effects
				(font
					(size 1.27 1.27)
					(thickness 0.15)
				)
				(justify right)
			)
		)
		(property "Value" "C_1u_0402"
			(at 267.97 41.91 0)
			(effects
				(font
					(size 1.27 1.27)
					(thickness 0.15)
				)
				(justify left bottom)
				(hide yes)
			)
		)
		(property "Footprint" "antmicro-footprints:C_0402_1005Metric"
			(at 270.51 41.91 0)
			(effects
				(font
					(size 1.27 1.27)
					(thickness 0.15)
				)
				(justify left bottom)
				(hide yes)
			)
		)
		(property "Datasheet" "https://product.tdk.com/en/search/capacitor/ceramic/mlcc/info?part_no=C1005X6S1A105K050BC"
			(at 273.05 41.91 0)
			(effects
				(font
					(size 1.27 1.27)
					(thickness 0.15)
				)
				(justify left bottom)
				(hide yes)
			)
		)
		(property "Description" ""
			(at 257.81 62.23 0)
			(effects
				(font
					(size 1.27 1.27)
				)
				(hide yes)
			)
		)
		(property "MPN" "C1005X6S1A105K050BC"
			(at 275.59 41.91 0)
			(effects
				(font
					(size 1.27 1.27)
					(thickness 0.15)
				)
				(justify left bottom)
				(hide yes)
			)
		)
		(property "Manufacturer" "TDK"
			(at 278.13 41.91 0)
			(effects
				(font
					(size 1.27 1.27)
					(thickness 0.15)
				)
				(justify left bottom)
				(hide yes)
			)
		)
		(property "License" "Apache-2.0"
			(at 280.67 41.91 0)
			(effects
				(font
					(size 1.27 1.27)
					(thickness 0.15)
				)
				(justify left bottom)
				(hide yes)
			)
		)
		(property "Author" "Antmicro"
			(at 283.21 41.91 0)
			(effects
				(font
					(size 1.27 1.27)
					(thickness 0.15)
				)
				(justify left bottom)
				(hide yes)
			)
		)
		(property "Val" "1u"
			(at 260.35 60.9535 90)
			(effects
				(font
					(size 1.27 1.27)
					(thickness 0.15)
				)
				(justify right)
			)
		)
		(property "Voltage" ""
			(at 285.75 41.91 0)
			(effects
				(font
					(size 1.27 1.27)
				)
				(justify left bottom)
				(hide yes)
			)
		)
		(property "Dielectric" ""
			(at 288.29 41.91 0)
			(effects
				(font
					(size 1.27 1.27)
				)
				(justify left bottom)
				(hide yes)
			)
		)
		(pin "1"
		)
		(pin "2"
		)
		(instances
			(project "cm4-baseboard"
				(path ""
					(reference "C802")
					(unit 1)
				)
			)
		)
	)
	(symbol
		(lib_id "antmicroCapacitors0402:C_470p_100V_0402")
		(at 331.47 121.92 90)
		(unit 1)
		(exclude_from_sim no)
		(in_bom yes)
		(on_board yes)
		(dnp no)
		(property "Reference" "C819"
			(at 332.994 118.11 90)
			(effects
				(font
					(size 1.27 1.27)
					(thickness 0.15)
				)
				(justify right)
			)
		)
		(property "Value" "C_470p_100V_0402"
			(at 341.63 101.6 0)
			(effects
				(font
					(size 1.27 1.27)
					(thickness 0.15)
				)
				(justify left bottom)
				(hide yes)
			)
		)
		(property "Footprint" "antmicro-footprints:C_0402_1005Metric"
			(at 344.17 101.6 0)
			(effects
				(font
					(size 1.27 1.27)
					(thickness 0.15)
				)
				(justify left bottom)
				(hide yes)
			)
		)
		(property "Datasheet" "https://search.murata.co.jp/Ceramy/image/img/A01X/G101/ENG/GRM1555C2A471JE01-01A.pdf"
			(at 346.71 101.6 0)
			(effects
				(font
					(size 1.27 1.27)
					(thickness 0.15)
				)
				(justify left bottom)
				(hide yes)
			)
		)
		(property "Description" "MLCC, SMD/SMT, 100V, 470pF, C0G/NP0, 0402 5%"
			(at 364.49 101.6 0)
			(effects
				(font
					(size 1.27 1.27)
				)
				(justify left bottom)
				(hide yes)
			)
		)
		(property "MPN" "GRM1555C2A471JE01D"
			(at 349.25 101.6 0)
			(effects
				(font
					(size 1.27 1.27)
					(thickness 0.15)
				)
				(justify left bottom)
				(hide yes)
			)
		)
		(property "Manufacturer" "Murata"
			(at 351.79 101.6 0)
			(effects
				(font
					(size 1.27 1.27)
					(thickness 0.15)
				)
				(justify left bottom)
				(hide yes)
			)
		)
		(property "License" "Apache-2.0"
			(at 354.33 101.6 0)
			(effects
				(font
					(size 1.27 1.27)
					(thickness 0.15)
				)
				(justify left bottom)
				(hide yes)
			)
		)
		(property "Author" "Antmicro"
			(at 356.87 101.6 0)
			(effects
				(font
					(size 1.27 1.27)
					(thickness 0.15)
				)
				(justify left bottom)
				(hide yes)
			)
		)
		(property "Val" "470p"
			(at 332.994 120.65 90)
			(effects
				(font
					(size 1.27 1.27)
					(thickness 0.15)
				)
				(justify right)
			)
		)
		(property "Voltage" "100V"
			(at 359.41 101.6 0)
			(effects
				(font
					(size 1.27 1.27)
				)
				(justify left bottom)
				(hide yes)
			)
		)
		(property "Dielectric" "C0G/NP0"
			(at 361.95 101.6 0)
			(effects
				(font
					(size 1.27 1.27)
				)
				(justify left bottom)
				(hide yes)
			)
		)
		(pin "1"
		)
		(pin "2"
		)
		(instances
			(project "cm4-baseboard"
				(path ""
					(reference "C819")
					(unit 1)
				)
			)
		)
	)
	(symbol
		(lib_id "antmicroFixedInductors:L_160n_0.28A_0603")
		(at 309.88 123.19 0)
		(unit 1)
		(exclude_from_sim no)
		(in_bom yes)
		(on_board yes)
		(dnp no)
		(property "Reference" "L802"
			(at 312.42 121.412 0)
			(effects
				(font
					(size 1.27 1.27)
					(thickness 0.15)
				)
			)
		)
		(property "Value" "L_160n_0.28A_0603"
			(at 323.85 125.73 0)
			(effects
				(font
					(size 1.27 1.27)
					(thickness 0.15)
				)
				(justify left bottom)
				(hide yes)
			)
		)
		(property "Footprint" "antmicro-footprints:L_TE_0603_1811Metric"
			(at 323.85 130.81 0)
			(effects
				(font
					(size 1.27 1.27)
					(thickness 0.15)
				)
				(justify left bottom)
				(hide yes)
			)
		)
		(property "Datasheet" "https://www.te.com/commerce/DocumentDelivery/DDEController?Action=showdoc&DocId=Data+Sheet%7F1773163%7FE%7Fpdf%7FEnglish%7FENG_DS_1773163_E.pdf"
			(at 323.85 133.35 0)
			(effects
				(font
					(size 1.27 1.27)
					(thickness 0.15)
				)
				(justify left bottom)
				(hide yes)
			)
		)
		(property "Description" "RF Inductor - 160 nH, 5%, 280 mA, 0603"
			(at 323.85 153.67 0)
			(effects
				(font
					(size 1.27 1.27)
				)
				(justify left bottom)
				(hide yes)
			)
		)
		(property "Val" "160 nH"
			(at 312.674 124.714 0)
			(effects
				(font
					(size 1.27 1.27)
					(thickness 0.15)
				)
			)
		)
		(property "Manufacturer" "TE Connectivity"
			(at 323.85 135.89 0)
			(effects
				(font
					(size 1.27 1.27)
					(thickness 0.15)
				)
				(justify left bottom)
				(hide yes)
			)
		)
		(property "MPN" "36501JR16JTDG"
			(at 323.85 138.43 0)
			(effects
				(font
					(size 1.27 1.27)
					(thickness 0.15)
				)
				(justify left bottom)
				(hide yes)
			)
		)
		(property "ISat" ""
			(at 323.85 139.7 0)
			(effects
				(font
					(size 1.27 1.27)
				)
				(justify left)
				(hide yes)
			)
		)
		(property "IMax" "0.28 A"
			(at 323.85 143.51 0)
			(effects
				(font
					(size 1.27 1.27)
					(thickness 0.15)
				)
				(justify left bottom)
				(hide yes)
			)
		)
		(property "Size" "1.8 x 1.12"
			(at 323.85 146.05 0)
			(effects
				(font
					(size 1.27 1.27)
					(thickness 0.15)
				)
				(justify left bottom)
				(hide yes)
			)
		)
		(property "Author" "Antmicro"
			(at 323.85 148.59 0)
			(effects
				(font
					(size 1.27 1.27)
					(thickness 0.15)
				)
				(justify left bottom)
				(hide yes)
			)
		)
		(property "License" "Apache-2.0"
			(at 323.85 151.13 0)
			(effects
				(font
					(size 1.27 1.27)
					(thickness 0.15)
				)
				(justify left bottom)
				(hide yes)
			)
		)
		(pin "1"
		)
		(pin "2"
		)
		(instances
			(project ""
				(path ""
					(reference "L802")
					(unit 1)
				)
			)
		)
	)
	(symbol
		(lib_id "antmicroResistors0402:R_2k2_0402")
		(at 331.47 106.68 270)
		(mirror x)
		(unit 1)
		(exclude_from_sim no)
		(in_bom yes)
		(on_board yes)
		(dnp no)
		(property "Reference" "R807"
			(at 329.946 102.87 90)
			(effects
				(font
					(size 1.27 1.27)
					(thickness 0.15)
				)
				(justify right)
			)
		)
		(property "Value" "R_2k2_0402"
			(at 318.77 86.36 0)
			(effects
				(font
					(size 1.27 1.27)
					(thickness 0.15)
				)
				(justify left bottom)
				(hide yes)
			)
		)
		(property "Footprint" "antmicro-footprints:R_0402_1005Metric"
			(at 316.23 86.36 0)
			(effects
				(font
					(size 1.27 1.27)
					(thickness 0.15)
				)
				(justify left bottom)
				(hide yes)
			)
		)
		(property "Datasheet" "https://www.bourns.com/docs/product-datasheets/cr.pdf"
			(at 313.69 86.36 0)
			(effects
				(font
					(size 1.27 1.27)
					(thickness 0.15)
				)
				(justify left bottom)
				(hide yes)
			)
		)
		(property "Description" "SMD Chip Resistor, 2.2 kohm, ± 1%, 62.5 mW, 0402 [1005 Metric], Thick Film, General Purpose"
			(at 300.99 86.36 0)
			(effects
				(font
					(size 1.27 1.27)
				)
				(justify left bottom)
				(hide yes)
			)
		)
		(property "MPN" "CR0402-FX-2201GLF"
			(at 311.15 86.36 0)
			(effects
				(font
					(size 1.27 1.27)
					(thickness 0.15)
				)
				(justify left bottom)
				(hide yes)
			)
		)
		(property "Manufacturer" "Bourns"
			(at 308.61 86.36 0)
			(effects
				(font
					(size 1.27 1.27)
					(thickness 0.15)
				)
				(justify left bottom)
				(hide yes)
			)
		)
		(property "License" "Apache-2.0"
			(at 306.07 86.36 0)
			(effects
				(font
					(size 1.27 1.27)
					(thickness 0.15)
				)
				(justify left bottom)
				(hide yes)
			)
		)
		(property "Author" "Antmicro"
			(at 303.53 86.36 0)
			(effects
				(font
					(size 1.27 1.27)
					(thickness 0.15)
				)
				(justify left bottom)
				(hide yes)
			)
		)
		(property "Val" "2k2"
			(at 329.946 105.41 90)
			(effects
				(font
					(size 1.27 1.27)
					(thickness 0.15)
				)
				(justify right)
			)
		)
		(property "Tolerance" "1%"
			(at 321.31 86.36 0)
			(effects
				(font
					(size 1.27 1.27)
				)
				(justify left bottom)
				(hide yes)
			)
		)
		(pin "2"
		)
		(pin "1"
		)
		(instances
			(project ""
				(path ""
					(reference "R807")
					(unit 1)
				)
			)
		)
	)
	(symbol
		(lib_id "antmicropower:GND")
		(at 243.84 133.35 0)
		(unit 1)
		(exclude_from_sim no)
		(in_bom yes)
		(on_board yes)
		(dnp no)
		(property "Reference" "#PWR0826"
			(at 252.73 135.89 0)
			(effects
				(font
					(size 1.27 1.27)
					(thickness 0.15)
				)
				(justify left bottom)
				(hide yes)
			)
		)
		(property "Value" "GND"
			(at 243.84 137.16 0)
			(effects
				(font
					(size 1.27 1.27)
					(thickness 0.15)
				)
			)
		)
		(property "Footprint" ""
			(at 252.73 140.97 0)
			(effects
				(font
					(size 1.27 1.27)
					(thickness 0.15)
				)
				(justify left bottom)
				(hide yes)
			)
		)
		(property "Datasheet" ""
			(at 252.73 146.05 0)
			(effects
				(font
					(size 1.27 1.27)
					(thickness 0.15)
				)
				(justify left bottom)
				(hide yes)
			)
		)
		(property "Description" ""
			(at 243.84 133.35 0)
			(effects
				(font
					(size 1.27 1.27)
				)
				(hide yes)
			)
		)
		(property "Author" "Antmicro"
			(at 252.73 140.97 0)
			(effects
				(font
					(size 1.27 1.27)
					(thickness 0.15)
				)
				(justify left bottom)
				(hide yes)
			)
		)
		(property "License" "Apache-2.0"
			(at 252.73 143.51 0)
			(effects
				(font
					(size 1.27 1.27)
					(thickness 0.15)
				)
				(justify left bottom)
				(hide yes)
			)
		)
		(pin "1"
		)
		(instances
			(project "cm4-baseboard"
				(path ""
					(reference "#PWR0826")
					(unit 1)
				)
			)
		)
	)
	(symbol
		(lib_id "antmicropower:+3V3")
		(at 248.92 209.55 0)
		(unit 1)
		(exclude_from_sim no)
		(in_bom yes)
		(on_board yes)
		(dnp no)
		(property "Reference" "#PWR039"
			(at 264.16 212.09 0)
			(effects
				(font
					(size 1.27 1.27)
					(thickness 0.15)
				)
				(justify left bottom)
				(hide yes)
			)
		)
		(property "Value" "+3V3"
			(at 248.92 204.47 0)
			(effects
				(font
					(size 1.27 1.27)
					(thickness 0.15)
				)
			)
		)
		(property "Footprint" ""
			(at 264.16 217.17 0)
			(effects
				(font
					(size 1.27 1.27)
					(thickness 0.15)
				)
				(justify left bottom)
				(hide yes)
			)
		)
		(property "Datasheet" ""
			(at 264.16 219.71 0)
			(effects
				(font
					(size 1.27 1.27)
					(thickness 0.15)
				)
				(justify left bottom)
				(hide yes)
			)
		)
		(property "Description" ""
			(at 248.92 209.55 0)
			(effects
				(font
					(size 1.27 1.27)
				)
				(hide yes)
			)
		)
		(property "Author" "Antmicro"
			(at 264.16 217.17 0)
			(effects
				(font
					(size 1.27 1.27)
					(thickness 0.15)
				)
				(justify left bottom)
				(hide yes)
			)
		)
		(property "License" "Apache-2.0"
			(at 264.16 219.71 0)
			(effects
				(font
					(size 1.27 1.27)
					(thickness 0.15)
				)
				(justify left bottom)
				(hide yes)
			)
		)
		(pin "1"
		)
		(instances
			(project "cm4-baseboard"
				(path ""
					(reference "#PWR039")
					(unit 1)
				)
			)
		)
	)
	(symbol
		(lib_id "antmicroTVSDiodes:PUSB3F96X_PASS")
		(at 182.88 186.69 0)
		(unit 1)
		(exclude_from_sim no)
		(in_bom yes)
		(on_board yes)
		(dnp no)
		(fields_autoplaced yes)
		(property "Reference" "D808"
			(at 196.85 189.2299 0)
			(effects
				(font
					(size 1.27 1.27)
					(thickness 0.15)
				)
				(justify left)
			)
		)
		(property "Value" "PUSB3F96X_PASS"
			(at 208.28 194.31 0)
			(effects
				(font
					(size 1.27 1.27)
					(thickness 0.15)
				)
				(justify left bottom)
				(hide yes)
			)
		)
		(property "Footprint" "antmicro-footprints:Nexperia_DFN-10_2.5x1mm_P0.5mm"
			(at 208.28 196.85 0)
			(effects
				(font
					(size 1.27 1.27)
					(thickness 0.15)
				)
				(justify left bottom)
				(hide yes)
			)
		)
		(property "Datasheet" "https://mouser.com/datasheet/2/916/PUSB3F96-1600324.pdf"
			(at 208.28 199.39 0)
			(effects
				(font
					(size 1.27 1.27)
					(thickness 0.15)
				)
				(justify left bottom)
				(hide yes)
			)
		)
		(property "Description" ""
			(at 182.88 186.69 0)
			(effects
				(font
					(size 1.27 1.27)
				)
				(hide yes)
			)
		)
		(property "Manufacturer" "Nexperia"
			(at 208.28 201.93 0)
			(effects
				(font
					(size 1.27 1.27)
					(thickness 0.15)
				)
				(justify left bottom)
				(hide yes)
			)
		)
		(property "MPN" "PUSB3F96X"
			(at 196.85 191.7699 0)
			(effects
				(font
					(size 1.27 1.27)
					(thickness 0.15)
				)
				(justify left)
			)
		)
		(property "Author" "Antmicro"
			(at 208.28 204.47 0)
			(effects
				(font
					(size 1.27 1.27)
					(thickness 0.15)
				)
				(justify left bottom)
				(hide yes)
			)
		)
		(property "License" "Apache-2.0"
			(at 208.28 207.01 0)
			(effects
				(font
					(size 1.27 1.27)
					(thickness 0.15)
				)
				(justify left bottom)
				(hide yes)
			)
		)
		(pin "1"
		)
		(pin "10"
		)
		(pin "2"
		)
		(pin "3"
		)
		(pin "4"
		)
		(pin "5"
		)
		(pin "6"
		)
		(pin "7"
		)
		(pin "8"
		)
		(pin "9"
		)
		(instances
			(project "cm4-baseboard"
				(path ""
					(reference "D808")
					(unit 1)
				)
			)
		)
	)
	(symbol
		(lib_id "antmicroCapacitors0402:C_4u7_0402")
		(at 248.92 87.63 90)
		(unit 1)
		(exclude_from_sim no)
		(in_bom yes)
		(on_board yes)
		(dnp no)
		(fields_autoplaced yes)
		(property "Reference" "C801"
			(at 250.19 83.82 90)
			(effects
				(font
					(size 1.27 1.27)
					(thickness 0.15)
				)
				(justify right)
			)
		)
		(property "Value" "C_4u7_0402"
			(at 259.08 67.31 0)
			(effects
				(font
					(size 1.27 1.27)
					(thickness 0.15)
				)
				(justify left bottom)
				(hide yes)
			)
		)
		(property "Footprint" "antmicro-footprints:C_0402_1005Metric"
			(at 261.62 67.31 0)
			(effects
				(font
					(size 1.27 1.27)
					(thickness 0.15)
				)
				(justify left bottom)
				(hide yes)
			)
		)
		(property "Datasheet" "https://www.murata.com/products/productdetail?partno=GRM155R61A475MEAA%23"
			(at 264.16 67.31 0)
			(effects
				(font
					(size 1.27 1.27)
					(thickness 0.15)
				)
				(justify left bottom)
				(hide yes)
			)
		)
		(property "Description" ""
			(at 248.92 87.63 0)
			(effects
				(font
					(size 1.27 1.27)
				)
				(hide yes)
			)
		)
		(property "MPN" "GRM155R61A475MEAAD"
			(at 266.7 67.31 0)
			(effects
				(font
					(size 1.27 1.27)
					(thickness 0.15)
				)
				(justify left bottom)
				(hide yes)
			)
		)
		(property "Manufacturer" "Murata"
			(at 269.24 67.31 0)
			(effects
				(font
					(size 1.27 1.27)
					(thickness 0.15)
				)
				(justify left bottom)
				(hide yes)
			)
		)
		(property "License" "Apache-2.0"
			(at 271.78 67.31 0)
			(effects
				(font
					(size 1.27 1.27)
					(thickness 0.15)
				)
				(justify left bottom)
				(hide yes)
			)
		)
		(property "Author" "Antmicro"
			(at 274.32 67.31 0)
			(effects
				(font
					(size 1.27 1.27)
					(thickness 0.15)
				)
				(justify left bottom)
				(hide yes)
			)
		)
		(property "Val" "4u7"
			(at 250.19 86.36 90)
			(effects
				(font
					(size 1.27 1.27)
					(thickness 0.15)
				)
				(justify right)
			)
		)
		(property "Voltage" ""
			(at 276.86 67.31 0)
			(effects
				(font
					(size 1.27 1.27)
				)
				(justify left bottom)
				(hide yes)
			)
		)
		(property "Dielectric" ""
			(at 279.4 67.31 0)
			(effects
				(font
					(size 1.27 1.27)
				)
				(justify left bottom)
				(hide yes)
			)
		)
		(pin "1"
		)
		(pin "2"
		)
		(instances
			(project "cm4-baseboard"
				(path ""
					(reference "C801")
					(unit 1)
				)
			)
		)
	)
	(symbol
		(lib_id "antmicroResonators:Resonator_32.768kHz_CM7V-T1A")
		(at 288.29 231.14 180)
		(unit 1)
		(exclude_from_sim no)
		(in_bom yes)
		(on_board yes)
		(dnp no)
		(property "Reference" "Y802"
			(at 284.48 237.49 0)
			(effects
				(font
					(size 1.27 1.27)
					(thickness 0.15)
				)
			)
		)
		(property "Value" "Resonator_32.768kHz_CM7V-T1A"
			(at 273.05 220.98 0)
			(effects
				(font
					(size 1.27 1.27)
					(thickness 0.15)
				)
				(justify left bottom)
				(hide yes)
			)
		)
		(property "Footprint" "antmicro-footprints:Resonator_SMD_MicroCrystal_CM7V-T1A_3.2x1.5x0.65mm"
			(at 273.05 218.44 0)
			(effects
				(font
					(size 1.27 1.27)
					(thickness 0.15)
				)
				(justify left bottom)
				(hide yes)
			)
		)
		(property "Datasheet" "https://www.microcrystal.com/fileadmin/Media/Products/32kHz/Datasheet/CM7V-T1A.pdf"
			(at 273.05 215.9 0)
			(effects
				(font
					(size 1.27 1.27)
					(thickness 0.15)
				)
				(justify left bottom)
				(hide yes)
			)
		)
		(property "Description" "Crystal, 32.768 kHz, SMD, 3.2mm x 1.5mm, 12.5 pF, 20 ppm, CC7V-T1A"
			(at 273.05 200.66 0)
			(effects
				(font
					(size 1.27 1.27)
					(thickness 0.15)
				)
				(justify left bottom)
				(hide yes)
			)
		)
		(property "MPN" "CM7V-T1A-32.768kHz-12.5pF-20PPM-TC-QA"
			(at 273.05 210.82 0)
			(effects
				(font
					(size 1.27 1.27)
					(thickness 0.15)
				)
				(justify left bottom)
				(hide yes)
			)
		)
		(property "Manufacturer" "Micro Crystal"
			(at 273.05 208.28 0)
			(effects
				(font
					(size 1.27 1.27)
					(thickness 0.15)
				)
				(justify left bottom)
				(hide yes)
			)
		)
		(property "Val" "32.768 kHz"
			(at 284.48 234.95 0)
			(effects
				(font
					(size 1.27 1.27)
					(thickness 0.15)
				)
			)
		)
		(property "Author" "Antmicro"
			(at 273.05 205.74 0)
			(effects
				(font
					(size 1.27 1.27)
					(thickness 0.15)
				)
				(justify left bottom)
				(hide yes)
			)
		)
		(property "License" "Apache-2.0"
			(at 273.05 203.2 0)
			(effects
				(font
					(size 1.27 1.27)
					(thickness 0.15)
				)
				(justify left bottom)
				(hide yes)
			)
		)
		(pin "1"
		)
		(pin "2"
		)
		(instances
			(project "cm4-baseboard"
				(path ""
					(reference "Y802")
					(unit 1)
				)
			)
		)
	)
	(symbol
		(lib_name "R_0R_0402_2")
		(lib_id "antmicroResistors0402:R_0R_0402")
		(at 364.49 107.95 0)
		(unit 1)
		(exclude_from_sim no)
		(in_bom yes)
		(on_board yes)
		(dnp no)
		(property "Reference" "R809"
			(at 367.03 103.124 0)
			(effects
				(font
					(size 1.27 1.27)
					(thickness 0.15)
				)
			)
		)
		(property "Value" "R_0R_0402"
			(at 384.81 120.65 0)
			(effects
				(font
					(size 1.27 1.27)
					(thickness 0.15)
				)
				(justify left bottom)
				(hide yes)
			)
		)
		(property "Footprint" "antmicro-footprints:R_0402_1005Metric"
			(at 384.81 123.19 0)
			(effects
				(font
					(size 1.27 1.27)
					(thickness 0.15)
				)
				(justify left bottom)
				(hide yes)
			)
		)
		(property "Datasheet" "https://industrial.panasonic.com/cdbs/www-data/pdf/RDA0000/AOA0000C301.pdf"
			(at 384.81 125.73 0)
			(effects
				(font
					(size 1.27 1.27)
					(thickness 0.15)
				)
				(justify left bottom)
				(hide yes)
			)
		)
		(property "Description" "SMD Chip Resistor, Jumper, 0 ohm, 100 mW, 0402 [1005 Metric], Thick Film, General Purpose"
			(at 384.81 140.97 0)
			(effects
				(font
					(size 1.27 1.27)
				)
				(justify left bottom)
				(hide yes)
			)
		)
		(property "MPN" "ERJ2GE0R00X"
			(at 384.81 128.27 0)
			(effects
				(font
					(size 1.27 1.27)
					(thickness 0.15)
				)
				(justify left bottom)
				(hide yes)
			)
		)
		(property "Manufacturer" "Panasonic"
			(at 384.81 130.81 0)
			(effects
				(font
					(size 1.27 1.27)
					(thickness 0.15)
				)
				(justify left bottom)
				(hide yes)
			)
		)
		(property "License" "Apache-2.0"
			(at 384.81 133.35 0)
			(effects
				(font
					(size 1.27 1.27)
					(thickness 0.15)
				)
				(justify left bottom)
				(hide yes)
			)
		)
		(property "Author" "Antmicro"
			(at 384.81 135.89 0)
			(effects
				(font
					(size 1.27 1.27)
					(thickness 0.15)
				)
				(justify left bottom)
				(hide yes)
			)
		)
		(property "Val" "0R"
			(at 367.03 105.664 0)
			(effects
				(font
					(size 1.27 1.27)
					(thickness 0.15)
				)
			)
		)
		(property "Tolerance" "~"
			(at 384.81 118.11 0)
			(effects
				(font
					(size 1.27 1.27)
				)
				(justify left bottom)
				(hide yes)
			)
		)
		(property "Current" "1A"
			(at 384.81 138.43 0)
			(effects
				(font
					(size 1.27 1.27)
					(thickness 0.15)
				)
				(justify left bottom)
				(hide yes)
			)
		)
		(pin "2"
		)
		(pin "1"
		)
		(instances
			(project ""
				(path ""
					(reference "R809")
					(unit 1)
				)
			)
		)
	)
	(symbol
		(lib_id "antmicropower:GND")
		(at 152.4 114.3 0)
		(unit 1)
		(exclude_from_sim no)
		(in_bom yes)
		(on_board yes)
		(dnp no)
		(property "Reference" "#PWR0817"
			(at 161.29 116.84 0)
			(effects
				(font
					(size 1.27 1.27)
					(thickness 0.15)
				)
				(justify left bottom)
				(hide yes)
			)
		)
		(property "Value" "GND"
			(at 152.4 119.38 0)
			(effects
				(font
					(size 1.27 1.27)
					(thickness 0.15)
				)
			)
		)
		(property "Footprint" ""
			(at 161.29 121.92 0)
			(effects
				(font
					(size 1.27 1.27)
					(thickness 0.15)
				)
				(justify left bottom)
				(hide yes)
			)
		)
		(property "Datasheet" ""
			(at 161.29 127 0)
			(effects
				(font
					(size 1.27 1.27)
					(thickness 0.15)
				)
				(justify left bottom)
				(hide yes)
			)
		)
		(property "Description" ""
			(at 152.4 114.3 0)
			(effects
				(font
					(size 1.27 1.27)
				)
				(hide yes)
			)
		)
		(property "Author" "Antmicro"
			(at 161.29 121.92 0)
			(effects
				(font
					(size 1.27 1.27)
					(thickness 0.15)
				)
				(justify left bottom)
				(hide yes)
			)
		)
		(property "License" "Apache-2.0"
			(at 161.29 124.46 0)
			(effects
				(font
					(size 1.27 1.27)
					(thickness 0.15)
				)
				(justify left bottom)
				(hide yes)
			)
		)
		(pin "1"
		)
		(instances
			(project "cm4-baseboard"
				(path ""
					(reference "#PWR0817")
					(unit 1)
				)
			)
		)
	)
	(symbol
		(lib_id "antmicroFixedInductors:L_160n_0.28A_0603")
		(at 309.88 107.95 0)
		(unit 1)
		(exclude_from_sim no)
		(in_bom yes)
		(on_board yes)
		(dnp no)
		(property "Reference" "L801"
			(at 312.42 105.918 0)
			(effects
				(font
					(size 1.27 1.27)
					(thickness 0.15)
				)
			)
		)
		(property "Value" "L_160n_0.28A_0603"
			(at 323.85 110.49 0)
			(effects
				(font
					(size 1.27 1.27)
					(thickness 0.15)
				)
				(justify left bottom)
				(hide yes)
			)
		)
		(property "Footprint" "antmicro-footprints:L_TE_0603_1811Metric"
			(at 323.85 115.57 0)
			(effects
				(font
					(size 1.27 1.27)
					(thickness 0.15)
				)
				(justify left bottom)
				(hide yes)
			)
		)
		(property "Datasheet" "https://www.te.com/commerce/DocumentDelivery/DDEController?Action=showdoc&DocId=Data+Sheet%7F1773163%7FE%7Fpdf%7FEnglish%7FENG_DS_1773163_E.pdf"
			(at 323.85 118.11 0)
			(effects
				(font
					(size 1.27 1.27)
					(thickness 0.15)
				)
				(justify left bottom)
				(hide yes)
			)
		)
		(property "Description" "RF Inductor - 160 nH, 5%, 280 mA, 0603"
			(at 323.85 138.43 0)
			(effects
				(font
					(size 1.27 1.27)
				)
				(justify left bottom)
				(hide yes)
			)
		)
		(property "Val" "160 nH"
			(at 312.674 109.474 0)
			(effects
				(font
					(size 1.27 1.27)
					(thickness 0.15)
				)
			)
		)
		(property "Manufacturer" "TE Connectivity"
			(at 323.85 120.65 0)
			(effects
				(font
					(size 1.27 1.27)
					(thickness 0.15)
				)
				(justify left bottom)
				(hide yes)
			)
		)
		(property "MPN" "36501JR16JTDG"
			(at 323.85 123.19 0)
			(effects
				(font
					(size 1.27 1.27)
					(thickness 0.15)
				)
				(justify left bottom)
				(hide yes)
			)
		)
		(property "ISat" ""
			(at 323.85 124.46 0)
			(effects
				(font
					(size 1.27 1.27)
				)
				(justify left)
				(hide yes)
			)
		)
		(property "IMax" "0.28 A"
			(at 323.85 128.27 0)
			(effects
				(font
					(size 1.27 1.27)
					(thickness 0.15)
				)
				(justify left bottom)
				(hide yes)
			)
		)
		(property "Size" "1.8 x 1.12"
			(at 323.85 130.81 0)
			(effects
				(font
					(size 1.27 1.27)
					(thickness 0.15)
				)
				(justify left bottom)
				(hide yes)
			)
		)
		(property "Author" "Antmicro"
			(at 323.85 133.35 0)
			(effects
				(font
					(size 1.27 1.27)
					(thickness 0.15)
				)
				(justify left bottom)
				(hide yes)
			)
		)
		(property "License" "Apache-2.0"
			(at 323.85 135.89 0)
			(effects
				(font
					(size 1.27 1.27)
					(thickness 0.15)
				)
				(justify left bottom)
				(hide yes)
			)
		)
		(pin "1"
		)
		(pin "2"
		)
		(instances
			(project "cm4-baseboard"
				(path ""
					(reference "L801")
					(unit 1)
				)
			)
		)
	)
	(symbol
		(lib_id "antmicroResonators:Resonator_27.12MHz_XRCGB")
		(at 311.15 158.75 0)
		(unit 1)
		(exclude_from_sim no)
		(in_bom yes)
		(on_board yes)
		(dnp no)
		(property "Reference" "Y801"
			(at 314.96 152.4 0)
			(effects
				(font
					(size 1.27 1.27)
					(thickness 0.15)
				)
			)
		)
		(property "Value" "Resonator_27.12MHz_XRCGB"
			(at 334.01 166.37 0)
			(effects
				(font
					(size 1.27 1.27)
					(thickness 0.15)
				)
				(justify left bottom)
				(hide yes)
			)
		)
		(property "Footprint" "antmicro-footprints:Resonator_SMD_Murata_XRCGB_2x1.6x0.65mm"
			(at 334.01 168.91 0)
			(effects
				(font
					(size 1.27 1.27)
					(thickness 0.15)
				)
				(justify left bottom)
				(hide yes)
			)
		)
		(property "Datasheet" "https://www.murata.com/products/productdata/8801078247454/SPEC-XRCGB27M120F3M13R0.pdf?1541043011000"
			(at 334.01 171.45 0)
			(effects
				(font
					(size 1.27 1.27)
					(thickness 0.15)
				)
				(justify left bottom)
				(hide yes)
			)
		)
		(property "Description" ""
			(at 311.15 158.75 0)
			(effects
				(font
					(size 1.27 1.27)
				)
				(hide yes)
			)
		)
		(property "MPN" "XRCGB27M120F3M13R0"
			(at 334.01 173.99 0)
			(effects
				(font
					(size 1.27 1.27)
					(thickness 0.15)
				)
				(justify left bottom)
				(hide yes)
			)
		)
		(property "Manufacturer" "Murata"
			(at 334.01 176.53 0)
			(effects
				(font
					(size 1.27 1.27)
					(thickness 0.15)
				)
				(justify left bottom)
				(hide yes)
			)
		)
		(property "Author" "Antmicro"
			(at 334.01 179.07 0)
			(effects
				(font
					(size 1.27 1.27)
					(thickness 0.15)
				)
				(justify left bottom)
				(hide yes)
			)
		)
		(property "License" "Apache-2.0"
			(at 334.01 181.61 0)
			(effects
				(font
					(size 1.27 1.27)
					(thickness 0.15)
				)
				(justify left bottom)
				(hide yes)
			)
		)
		(property "Val" "27.12MHz"
			(at 314.96 154.94 0)
			(effects
				(font
					(size 1.27 1.27)
				)
			)
		)
		(property "CLoad" "10pF"
			(at 311.15 158.75 0)
			(effects
				(font
					(size 1.27 1.27)
				)
				(hide yes)
			)
		)
		(pin "1"
		)
		(pin "2"
		)
		(pin "3"
		)
		(pin "4"
		)
		(instances
			(project "cm4-baseboard"
				(path ""
					(reference "Y801")
					(unit 1)
				)
			)
		)
	)
	(symbol
		(lib_id "antmicroCapacitors0402:C_1n_0402")
		(at 309.88 130.81 0)
		(unit 1)
		(exclude_from_sim no)
		(in_bom yes)
		(on_board yes)
		(dnp no)
		(property "Reference" "C813"
			(at 315.722 129.54 0)
			(effects
				(font
					(size 1.27 1.27)
					(thickness 0.15)
				)
			)
		)
		(property "Value" "C_1n_0402"
			(at 330.2 140.97 0)
			(effects
				(font
					(size 1.27 1.27)
					(thickness 0.15)
				)
				(justify left bottom)
				(hide yes)
			)
		)
		(property "Footprint" "antmicro-footprints:C_0402_1005Metric"
			(at 330.2 143.51 0)
			(effects
				(font
					(size 1.27 1.27)
					(thickness 0.15)
				)
				(justify left bottom)
				(hide yes)
			)
		)
		(property "Datasheet" "https://www.murata.com/products/productdetail?partno=GRM1555C1H102JA01%23"
			(at 330.2 146.05 0)
			(effects
				(font
					(size 1.27 1.27)
					(thickness 0.15)
				)
				(justify left bottom)
				(hide yes)
			)
		)
		(property "Description" "SMD Multilayer Ceramic Capacitor, 1000 pF, 50 V, 0402 [1005 Metric], ± 5%, C0G / NP0, GRM Series"
			(at 330.2 163.83 0)
			(effects
				(font
					(size 1.27 1.27)
				)
				(justify left bottom)
				(hide yes)
			)
		)
		(property "MPN" "GRM1555C1H102JA01D"
			(at 330.2 148.59 0)
			(effects
				(font
					(size 1.27 1.27)
					(thickness 0.15)
				)
				(justify left bottom)
				(hide yes)
			)
		)
		(property "Manufacturer" "Murata"
			(at 330.2 151.13 0)
			(effects
				(font
					(size 1.27 1.27)
					(thickness 0.15)
				)
				(justify left bottom)
				(hide yes)
			)
		)
		(property "License" "Apache-2.0"
			(at 330.2 153.67 0)
			(effects
				(font
					(size 1.27 1.27)
					(thickness 0.15)
				)
				(justify left bottom)
				(hide yes)
			)
		)
		(property "Author" "Antmicro"
			(at 330.2 156.21 0)
			(effects
				(font
					(size 1.27 1.27)
					(thickness 0.15)
				)
				(justify left bottom)
				(hide yes)
			)
		)
		(property "Val" "1n"
			(at 315.976 131.826 0)
			(effects
				(font
					(size 1.27 1.27)
					(thickness 0.15)
				)
			)
		)
		(property "Voltage" "50V"
			(at 330.2 158.75 0)
			(effects
				(font
					(size 1.27 1.27)
				)
				(justify left bottom)
				(hide yes)
			)
		)
		(property "Dielectric" "C0G"
			(at 330.2 161.29 0)
			(effects
				(font
					(size 1.27 1.27)
				)
				(justify left bottom)
				(hide yes)
			)
		)
		(pin "1"
		)
		(pin "2"
		)
		(instances
			(project ""
				(path ""
					(reference "C813")
					(unit 1)
				)
			)
		)
	)
	(symbol
		(lib_id "antmicropower:+3V3")
		(at 243.84 114.3 0)
		(unit 1)
		(exclude_from_sim no)
		(in_bom yes)
		(on_board yes)
		(dnp no)
		(fields_autoplaced yes)
		(property "Reference" "#PWR0825"
			(at 259.08 116.84 0)
			(effects
				(font
					(size 1.27 1.27)
					(thickness 0.15)
				)
				(justify left bottom)
				(hide yes)
			)
		)
		(property "Value" "+3V3"
			(at 243.84 109.22 0)
			(effects
				(font
					(size 1.27 1.27)
					(thickness 0.15)
				)
			)
		)
		(property "Footprint" ""
			(at 259.08 121.92 0)
			(effects
				(font
					(size 1.27 1.27)
					(thickness 0.15)
				)
				(justify left bottom)
				(hide yes)
			)
		)
		(property "Datasheet" ""
			(at 259.08 124.46 0)
			(effects
				(font
					(size 1.27 1.27)
					(thickness 0.15)
				)
				(justify left bottom)
				(hide yes)
			)
		)
		(property "Description" ""
			(at 243.84 114.3 0)
			(effects
				(font
					(size 1.27 1.27)
				)
				(hide yes)
			)
		)
		(property "Author" "Antmicro"
			(at 259.08 121.92 0)
			(effects
				(font
					(size 1.27 1.27)
					(thickness 0.15)
				)
				(justify left bottom)
				(hide yes)
			)
		)
		(property "License" "Apache-2.0"
			(at 259.08 124.46 0)
			(effects
				(font
					(size 1.27 1.27)
					(thickness 0.15)
				)
				(justify left bottom)
				(hide yes)
			)
		)
		(pin "1"
		)
		(instances
			(project "cm4-baseboard"
				(path ""
					(reference "#PWR0825")
					(unit 1)
				)
			)
		)
	)
	(symbol
		(lib_id "antmicropower:+3V3")
		(at 236.22 114.3 0)
		(unit 1)
		(exclude_from_sim no)
		(in_bom yes)
		(on_board yes)
		(dnp no)
		(fields_autoplaced yes)
		(property "Reference" "#PWR0823"
			(at 251.46 116.84 0)
			(effects
				(font
					(size 1.27 1.27)
					(thickness 0.15)
				)
				(justify left bottom)
				(hide yes)
			)
		)
		(property "Value" "+3V3"
			(at 236.22 109.22 0)
			(effects
				(font
					(size 1.27 1.27)
					(thickness 0.15)
				)
			)
		)
		(property "Footprint" ""
			(at 251.46 121.92 0)
			(effects
				(font
					(size 1.27 1.27)
					(thickness 0.15)
				)
				(justify left bottom)
				(hide yes)
			)
		)
		(property "Datasheet" ""
			(at 251.46 124.46 0)
			(effects
				(font
					(size 1.27 1.27)
					(thickness 0.15)
				)
				(justify left bottom)
				(hide yes)
			)
		)
		(property "Description" ""
			(at 236.22 114.3 0)
			(effects
				(font
					(size 1.27 1.27)
				)
				(hide yes)
			)
		)
		(property "Author" "Antmicro"
			(at 251.46 121.92 0)
			(effects
				(font
					(size 1.27 1.27)
					(thickness 0.15)
				)
				(justify left bottom)
				(hide yes)
			)
		)
		(property "License" "Apache-2.0"
			(at 251.46 124.46 0)
			(effects
				(font
					(size 1.27 1.27)
					(thickness 0.15)
				)
				(justify left bottom)
				(hide yes)
			)
		)
		(pin "1"
		)
		(instances
			(project "cm4-baseboard"
				(path ""
					(reference "#PWR0823")
					(unit 1)
				)
			)
		)
	)
	(symbol
		(lib_id "antmicropower:GND")
		(at 257.81 76.2 0)
		(unit 1)
		(exclude_from_sim no)
		(in_bom yes)
		(on_board yes)
		(dnp no)
		(property "Reference" "#PWR0830"
			(at 266.7 78.74 0)
			(effects
				(font
					(size 1.27 1.27)
					(thickness 0.15)
				)
				(justify left bottom)
				(hide yes)
			)
		)
		(property "Value" "GND"
			(at 257.81 80.01 0)
			(effects
				(font
					(size 1.27 1.27)
					(thickness 0.15)
				)
			)
		)
		(property "Footprint" ""
			(at 266.7 83.82 0)
			(effects
				(font
					(size 1.27 1.27)
					(thickness 0.15)
				)
				(justify left bottom)
				(hide yes)
			)
		)
		(property "Datasheet" ""
			(at 266.7 88.9 0)
			(effects
				(font
					(size 1.27 1.27)
					(thickness 0.15)
				)
				(justify left bottom)
				(hide yes)
			)
		)
		(property "Description" ""
			(at 257.81 76.2 0)
			(effects
				(font
					(size 1.27 1.27)
				)
				(hide yes)
			)
		)
		(property "Author" "Antmicro"
			(at 266.7 83.82 0)
			(effects
				(font
					(size 1.27 1.27)
					(thickness 0.15)
				)
				(justify left bottom)
				(hide yes)
			)
		)
		(property "License" "Apache-2.0"
			(at 266.7 86.36 0)
			(effects
				(font
					(size 1.27 1.27)
					(thickness 0.15)
				)
				(justify left bottom)
				(hide yes)
			)
		)
		(pin "1"
		)
		(instances
			(project "cm4-baseboard"
				(path ""
					(reference "#PWR0830")
					(unit 1)
				)
			)
		)
	)
	(symbol
		(lib_id "antmicropower:GND")
		(at 374.65 118.11 0)
		(mirror y)
		(unit 1)
		(exclude_from_sim no)
		(in_bom yes)
		(on_board yes)
		(dnp no)
		(property "Reference" "#PWR0837"
			(at 365.76 120.65 0)
			(effects
				(font
					(size 1.27 1.27)
					(thickness 0.15)
				)
				(justify left bottom)
				(hide yes)
			)
		)
		(property "Value" "GND"
			(at 374.65 121.92 0)
			(effects
				(font
					(size 1.27 1.27)
					(thickness 0.15)
				)
			)
		)
		(property "Footprint" ""
			(at 365.76 125.73 0)
			(effects
				(font
					(size 1.27 1.27)
					(thickness 0.15)
				)
				(justify left bottom)
				(hide yes)
			)
		)
		(property "Datasheet" ""
			(at 365.76 130.81 0)
			(effects
				(font
					(size 1.27 1.27)
					(thickness 0.15)
				)
				(justify left bottom)
				(hide yes)
			)
		)
		(property "Description" ""
			(at 374.65 118.11 0)
			(effects
				(font
					(size 1.27 1.27)
				)
				(hide yes)
			)
		)
		(property "Author" "Antmicro"
			(at 365.76 125.73 0)
			(effects
				(font
					(size 1.27 1.27)
					(thickness 0.15)
				)
				(justify left bottom)
				(hide yes)
			)
		)
		(property "License" "Apache-2.0"
			(at 365.76 128.27 0)
			(effects
				(font
					(size 1.27 1.27)
					(thickness 0.15)
				)
				(justify left bottom)
				(hide yes)
			)
		)
		(pin "1"
		)
		(instances
			(project "cm4-baseboard"
				(path ""
					(reference "#PWR0837")
					(unit 1)
				)
			)
		)
	)
	(symbol
		(lib_id "antmicroResistors0402:R_10k_0402")
		(at 236.22 132.08 90)
		(unit 1)
		(exclude_from_sim no)
		(in_bom yes)
		(on_board yes)
		(dnp no)
		(fields_autoplaced yes)
		(property "Reference" "R804"
			(at 237.49 128.27 90)
			(effects
				(font
					(size 1.27 1.27)
					(thickness 0.15)
				)
				(justify right)
			)
		)
		(property "Value" "R_10k_0402"
			(at 248.92 111.76 0)
			(effects
				(font
					(size 1.27 1.27)
					(thickness 0.15)
				)
				(justify left bottom)
				(hide yes)
			)
		)
		(property "Footprint" "antmicro-footprints:R_0402_1005Metric"
			(at 251.46 111.76 0)
			(effects
				(font
					(size 1.27 1.27)
					(thickness 0.15)
				)
				(justify left bottom)
				(hide yes)
			)
		)
		(property "Datasheet" "https://www.bourns.com/docs/product-datasheets/cr.pdf"
			(at 254 111.76 0)
			(effects
				(font
					(size 1.27 1.27)
					(thickness 0.15)
				)
				(justify left bottom)
				(hide yes)
			)
		)
		(property "Description" ""
			(at 236.22 132.08 0)
			(effects
				(font
					(size 1.27 1.27)
				)
				(hide yes)
			)
		)
		(property "MPN" "CR0402-FX-1002GLF"
			(at 256.54 111.76 0)
			(effects
				(font
					(size 1.27 1.27)
					(thickness 0.15)
				)
				(justify left bottom)
				(hide yes)
			)
		)
		(property "Manufacturer" "Bourns"
			(at 259.08 111.76 0)
			(effects
				(font
					(size 1.27 1.27)
					(thickness 0.15)
				)
				(justify left bottom)
				(hide yes)
			)
		)
		(property "License" "Apache-2.0"
			(at 261.62 111.76 0)
			(effects
				(font
					(size 1.27 1.27)
					(thickness 0.15)
				)
				(justify left bottom)
				(hide yes)
			)
		)
		(property "Author" "Antmicro"
			(at 264.16 111.76 0)
			(effects
				(font
					(size 1.27 1.27)
					(thickness 0.15)
				)
				(justify left bottom)
				(hide yes)
			)
		)
		(property "Val" "10k"
			(at 237.49 130.81 90)
			(effects
				(font
					(size 1.27 1.27)
					(thickness 0.15)
				)
				(justify right)
			)
		)
		(property "Tolerance" "1%"
			(at 246.38 111.76 0)
			(effects
				(font
					(size 1.27 1.27)
				)
				(justify left bottom)
				(hide yes)
			)
		)
		(pin "1"
		)
		(pin "2"
		)
		(instances
			(project "cm4-baseboard"
				(path ""
					(reference "R804")
					(unit 1)
				)
			)
		)
	)
	(symbol
		(lib_id "antmicroResistors0402:R_0R_0402")
		(at 91.44 96.52 270)
		(mirror x)
		(unit 1)
		(exclude_from_sim no)
		(in_bom no)
		(on_board yes)
		(dnp yes)
		(property "Reference" "R801"
			(at 88.9 92.71 90)
			(effects
				(font
					(size 1.27 1.27)
					(thickness 0.15)
				)
				(justify right)
			)
		)
		(property "Value" "R_0R_0402"
			(at 78.74 76.2 0)
			(effects
				(font
					(size 1.27 1.27)
					(thickness 0.15)
				)
				(justify left bottom)
				(hide yes)
			)
		)
		(property "Footprint" "antmicro-footprints:R_0402_1005Metric"
			(at 76.2 76.2 0)
			(effects
				(font
					(size 1.27 1.27)
					(thickness 0.15)
				)
				(justify left bottom)
				(hide yes)
			)
		)
		(property "Datasheet" "https://industrial.panasonic.com/cdbs/www-data/pdf/RDA0000/AOA0000C301.pdf"
			(at 73.66 76.2 0)
			(effects
				(font
					(size 1.27 1.27)
					(thickness 0.15)
				)
				(justify left bottom)
				(hide yes)
			)
		)
		(property "Description" ""
			(at 91.44 96.52 0)
			(effects
				(font
					(size 1.27 1.27)
				)
				(hide yes)
			)
		)
		(property "MPN" "ERJ2GE0R00X"
			(at 71.12 76.2 0)
			(effects
				(font
					(size 1.27 1.27)
					(thickness 0.15)
				)
				(justify left bottom)
				(hide yes)
			)
		)
		(property "Manufacturer" "Panasonic"
			(at 68.58 76.2 0)
			(effects
				(font
					(size 1.27 1.27)
					(thickness 0.15)
				)
				(justify left bottom)
				(hide yes)
			)
		)
		(property "License" "Apache-2.0"
			(at 66.04 76.2 0)
			(effects
				(font
					(size 1.27 1.27)
					(thickness 0.15)
				)
				(justify left bottom)
				(hide yes)
			)
		)
		(property "Author" "Antmicro"
			(at 63.5 76.2 0)
			(effects
				(font
					(size 1.27 1.27)
					(thickness 0.15)
				)
				(justify left bottom)
				(hide yes)
			)
		)
		(property "Val" "0R"
			(at 88.9 95.25 90)
			(effects
				(font
					(size 1.27 1.27)
					(thickness 0.15)
				)
				(justify right)
			)
		)
		(property "Tolerance" "~"
			(at 81.28 76.2 0)
			(effects
				(font
					(size 1.27 1.27)
				)
				(justify left bottom)
				(hide yes)
			)
		)
		(property "Current" "1A"
			(at 60.96 76.2 0)
			(effects
				(font
					(size 1.27 1.27)
					(thickness 0.15)
				)
				(justify left bottom)
				(hide yes)
			)
		)
		(pin "1"
		)
		(pin "2"
		)
		(instances
			(project "cm4-baseboard"
				(path ""
					(reference "R801")
					(unit 1)
				)
			)
		)
	)
	(symbol
		(lib_id "antmicroCapacitors0402:C_36p_0402")
		(at 339.09 107.95 0)
		(unit 1)
		(exclude_from_sim no)
		(in_bom yes)
		(on_board yes)
		(dnp no)
		(property "Reference" "C821"
			(at 341.63 103.378 0)
			(effects
				(font
					(size 1.27 1.27)
					(thickness 0.15)
				)
			)
		)
		(property "Value" "C_36p_0402"
			(at 359.41 118.11 0)
			(effects
				(font
					(size 1.27 1.27)
					(thickness 0.15)
				)
				(justify left bottom)
				(hide yes)
			)
		)
		(property "Footprint" "antmicro-footprints:C_0402_1005Metric"
			(at 359.41 120.65 0)
			(effects
				(font
					(size 1.27 1.27)
					(thickness 0.15)
				)
				(justify left bottom)
				(hide yes)
			)
		)
		(property "Datasheet" "https://eu.mouser.com/datasheet/3/5926/1/C0GNP0_Dielectric.pdf"
			(at 359.41 123.19 0)
			(effects
				(font
					(size 1.27 1.27)
					(thickness 0.15)
				)
				(justify left bottom)
				(hide yes)
			)
		)
		(property "Description" "Multilayer Ceramic Capacitors MLCC, 36 pF, 25V, 0402, C0G, 5%"
			(at 359.41 140.97 0)
			(effects
				(font
					(size 1.27 1.27)
				)
				(justify left bottom)
				(hide yes)
			)
		)
		(property "MPN" "04023A360JAT2A"
			(at 359.41 125.73 0)
			(effects
				(font
					(size 1.27 1.27)
					(thickness 0.15)
				)
				(justify left bottom)
				(hide yes)
			)
		)
		(property "Manufacturer" "KYOCERA AVX"
			(at 359.41 128.27 0)
			(effects
				(font
					(size 1.27 1.27)
					(thickness 0.15)
				)
				(justify left bottom)
				(hide yes)
			)
		)
		(property "License" "Apache-2.0"
			(at 359.41 130.81 0)
			(effects
				(font
					(size 1.27 1.27)
					(thickness 0.15)
				)
				(justify left bottom)
				(hide yes)
			)
		)
		(property "Author" "Antmicro"
			(at 359.41 133.35 0)
			(effects
				(font
					(size 1.27 1.27)
					(thickness 0.15)
				)
				(justify left bottom)
				(hide yes)
			)
		)
		(property "Val" "36pF"
			(at 341.63 105.156 0)
			(effects
				(font
					(size 1.27 1.27)
					(thickness 0.15)
				)
			)
		)
		(property "Voltage" "25 V"
			(at 359.41 135.89 0)
			(effects
				(font
					(size 1.27 1.27)
				)
				(justify left bottom)
				(hide yes)
			)
		)
		(property "Dielectric" "C0G (NP0)"
			(at 359.41 138.43 0)
			(effects
				(font
					(size 1.27 1.27)
				)
				(justify left bottom)
				(hide yes)
			)
		)
		(pin "1"
		)
		(pin "2"
		)
		(instances
			(project ""
				(path ""
					(reference "C821")
					(unit 1)
				)
			)
		)
	)
	(symbol
		(lib_id "antmicroTVSDiodes:PUSB3F96X_PASS")
		(at 132.08 185.42 0)
		(unit 1)
		(exclude_from_sim no)
		(in_bom yes)
		(on_board yes)
		(dnp no)
		(fields_autoplaced yes)
		(property "Reference" "D802"
			(at 146.05 187.9599 0)
			(effects
				(font
					(size 1.27 1.27)
					(thickness 0.15)
				)
				(justify left)
			)
		)
		(property "Value" "PUSB3F96X_PASS"
			(at 157.48 193.04 0)
			(effects
				(font
					(size 1.27 1.27)
					(thickness 0.15)
				)
				(justify left bottom)
				(hide yes)
			)
		)
		(property "Footprint" "antmicro-footprints:Nexperia_DFN-10_2.5x1mm_P0.5mm"
			(at 157.48 195.58 0)
			(effects
				(font
					(size 1.27 1.27)
					(thickness 0.15)
				)
				(justify left bottom)
				(hide yes)
			)
		)
		(property "Datasheet" "https://mouser.com/datasheet/2/916/PUSB3F96-1600324.pdf"
			(at 157.48 198.12 0)
			(effects
				(font
					(size 1.27 1.27)
					(thickness 0.15)
				)
				(justify left bottom)
				(hide yes)
			)
		)
		(property "Description" ""
			(at 132.08 185.42 0)
			(effects
				(font
					(size 1.27 1.27)
				)
				(hide yes)
			)
		)
		(property "Manufacturer" "Nexperia"
			(at 157.48 200.66 0)
			(effects
				(font
					(size 1.27 1.27)
					(thickness 0.15)
				)
				(justify left bottom)
				(hide yes)
			)
		)
		(property "MPN" "PUSB3F96X"
			(at 146.05 190.4999 0)
			(effects
				(font
					(size 1.27 1.27)
					(thickness 0.15)
				)
				(justify left)
			)
		)
		(property "Author" "Antmicro"
			(at 157.48 203.2 0)
			(effects
				(font
					(size 1.27 1.27)
					(thickness 0.15)
				)
				(justify left bottom)
				(hide yes)
			)
		)
		(property "License" "Apache-2.0"
			(at 157.48 205.74 0)
			(effects
				(font
					(size 1.27 1.27)
					(thickness 0.15)
				)
				(justify left bottom)
				(hide yes)
			)
		)
		(pin "1"
		)
		(pin "10"
		)
		(pin "2"
		)
		(pin "3"
		)
		(pin "4"
		)
		(pin "5"
		)
		(pin "6"
		)
		(pin "7"
		)
		(pin "8"
		)
		(pin "9"
		)
		(instances
			(project "cm4-baseboard"
				(path ""
					(reference "D802")
					(unit 1)
				)
			)
		)
	)
	(symbol
		(lib_id "antmicropower:GND")
		(at 181.61 179.07 0)
		(unit 1)
		(exclude_from_sim no)
		(in_bom yes)
		(on_board yes)
		(dnp no)
		(fields_autoplaced yes)
		(property "Reference" "#PWR0819"
			(at 190.5 181.61 0)
			(effects
				(font
					(size 1.27 1.27)
					(thickness 0.15)
				)
				(justify left bottom)
				(hide yes)
			)
		)
		(property "Value" "GND"
			(at 181.61 184.15 0)
			(effects
				(font
					(size 1.27 1.27)
				)
			)
		)
		(property "Footprint" ""
			(at 190.5 186.69 0)
			(effects
				(font
					(size 1.27 1.27)
					(thickness 0.15)
				)
				(justify left bottom)
				(hide yes)
			)
		)
		(property "Datasheet" ""
			(at 190.5 191.77 0)
			(effects
				(font
					(size 1.27 1.27)
					(thickness 0.15)
				)
				(justify left bottom)
				(hide yes)
			)
		)
		(property "Description" ""
			(at 181.61 179.07 0)
			(effects
				(font
					(size 1.27 1.27)
				)
				(hide yes)
			)
		)
		(property "Author" "Antmicro"
			(at 190.5 186.69 0)
			(effects
				(font
					(size 1.27 1.27)
					(thickness 0.15)
				)
				(justify left bottom)
				(hide yes)
			)
		)
		(property "License" "Apache-2.0"
			(at 190.5 189.23 0)
			(effects
				(font
					(size 1.27 1.27)
					(thickness 0.15)
				)
				(justify left bottom)
				(hide yes)
			)
		)
		(pin "1"
		)
		(instances
			(project "cm4-baseboard"
				(path ""
					(reference "#PWR0819")
					(unit 1)
				)
			)
		)
	)
	(symbol
		(lib_id "antmicropower:GND")
		(at 58.42 228.6 0)
		(unit 1)
		(exclude_from_sim no)
		(in_bom yes)
		(on_board yes)
		(dnp no)
		(property "Reference" "#PWR0804"
			(at 67.31 231.14 0)
			(effects
				(font
					(size 1.27 1.27)
					(thickness 0.15)
				)
				(justify left bottom)
				(hide yes)
			)
		)
		(property "Value" "GND"
			(at 58.42 233.68 0)
			(effects
				(font
					(size 1.27 1.27)
					(thickness 0.15)
				)
			)
		)
		(property "Footprint" ""
			(at 67.31 236.22 0)
			(effects
				(font
					(size 1.27 1.27)
					(thickness 0.15)
				)
				(justify left bottom)
				(hide yes)
			)
		)
		(property "Datasheet" ""
			(at 67.31 241.3 0)
			(effects
				(font
					(size 1.27 1.27)
					(thickness 0.15)
				)
				(justify left bottom)
				(hide yes)
			)
		)
		(property "Description" ""
			(at 58.42 228.6 0)
			(effects
				(font
					(size 1.27 1.27)
				)
				(hide yes)
			)
		)
		(property "Author" "Antmicro"
			(at 67.31 236.22 0)
			(effects
				(font
					(size 1.27 1.27)
					(thickness 0.15)
				)
				(justify left bottom)
				(hide yes)
			)
		)
		(property "License" "Apache-2.0"
			(at 67.31 238.76 0)
			(effects
				(font
					(size 1.27 1.27)
					(thickness 0.15)
				)
				(justify left bottom)
				(hide yes)
			)
		)
		(pin "1"
		)
		(instances
			(project "cm4-baseboard"
				(path ""
					(reference "#PWR0804")
					(unit 1)
				)
			)
		)
	)
	(symbol
		(lib_id "antmicropower:+3V3")
		(at 300.99 213.36 0)
		(unit 1)
		(exclude_from_sim no)
		(in_bom yes)
		(on_board yes)
		(dnp no)
		(property "Reference" "#PWR042"
			(at 316.23 215.9 0)
			(effects
				(font
					(size 1.27 1.27)
					(thickness 0.15)
				)
				(justify left bottom)
				(hide yes)
			)
		)
		(property "Value" "+3V3"
			(at 300.99 208.28 0)
			(effects
				(font
					(size 1.27 1.27)
					(thickness 0.15)
				)
			)
		)
		(property "Footprint" ""
			(at 316.23 220.98 0)
			(effects
				(font
					(size 1.27 1.27)
					(thickness 0.15)
				)
				(justify left bottom)
				(hide yes)
			)
		)
		(property "Datasheet" ""
			(at 316.23 223.52 0)
			(effects
				(font
					(size 1.27 1.27)
					(thickness 0.15)
				)
				(justify left bottom)
				(hide yes)
			)
		)
		(property "Description" ""
			(at 300.99 213.36 0)
			(effects
				(font
					(size 1.27 1.27)
				)
				(hide yes)
			)
		)
		(property "Author" "Antmicro"
			(at 316.23 220.98 0)
			(effects
				(font
					(size 1.27 1.27)
					(thickness 0.15)
				)
				(justify left bottom)
				(hide yes)
			)
		)
		(property "License" "Apache-2.0"
			(at 316.23 223.52 0)
			(effects
				(font
					(size 1.27 1.27)
					(thickness 0.15)
				)
				(justify left bottom)
				(hide yes)
			)
		)
		(pin "1"
		)
		(instances
			(project "cm4-baseboard"
				(path ""
					(reference "#PWR042")
					(unit 1)
				)
			)
		)
	)
	(symbol
		(lib_id "antmicroResistors0402:R_10k_0402")
		(at 243.84 132.08 90)
		(unit 1)
		(exclude_from_sim no)
		(in_bom yes)
		(on_board yes)
		(dnp no)
		(fields_autoplaced yes)
		(property "Reference" "R806"
			(at 245.11 128.27 90)
			(effects
				(font
					(size 1.27 1.27)
					(thickness 0.15)
				)
				(justify right)
			)
		)
		(property "Value" "R_10k_0402"
			(at 256.54 111.76 0)
			(effects
				(font
					(size 1.27 1.27)
					(thickness 0.15)
				)
				(justify left bottom)
				(hide yes)
			)
		)
		(property "Footprint" "antmicro-footprints:R_0402_1005Metric"
			(at 259.08 111.76 0)
			(effects
				(font
					(size 1.27 1.27)
					(thickness 0.15)
				)
				(justify left bottom)
				(hide yes)
			)
		)
		(property "Datasheet" "https://www.bourns.com/docs/product-datasheets/cr.pdf"
			(at 261.62 111.76 0)
			(effects
				(font
					(size 1.27 1.27)
					(thickness 0.15)
				)
				(justify left bottom)
				(hide yes)
			)
		)
		(property "Description" ""
			(at 243.84 132.08 0)
			(effects
				(font
					(size 1.27 1.27)
				)
				(hide yes)
			)
		)
		(property "MPN" "CR0402-FX-1002GLF"
			(at 264.16 111.76 0)
			(effects
				(font
					(size 1.27 1.27)
					(thickness 0.15)
				)
				(justify left bottom)
				(hide yes)
			)
		)
		(property "Manufacturer" "Bourns"
			(at 266.7 111.76 0)
			(effects
				(font
					(size 1.27 1.27)
					(thickness 0.15)
				)
				(justify left bottom)
				(hide yes)
			)
		)
		(property "License" "Apache-2.0"
			(at 269.24 111.76 0)
			(effects
				(font
					(size 1.27 1.27)
					(thickness 0.15)
				)
				(justify left bottom)
				(hide yes)
			)
		)
		(property "Author" "Antmicro"
			(at 271.78 111.76 0)
			(effects
				(font
					(size 1.27 1.27)
					(thickness 0.15)
				)
				(justify left bottom)
				(hide yes)
			)
		)
		(property "Val" "10k"
			(at 245.11 130.81 90)
			(effects
				(font
					(size 1.27 1.27)
					(thickness 0.15)
				)
				(justify right)
			)
		)
		(property "Tolerance" "1%"
			(at 254 111.76 0)
			(effects
				(font
					(size 1.27 1.27)
				)
				(justify left bottom)
				(hide yes)
			)
		)
		(pin "1"
		)
		(pin "2"
		)
		(instances
			(project "cm4-baseboard"
				(path ""
					(reference "R806")
					(unit 1)
				)
			)
		)
	)
	(symbol
		(lib_id "antmicroTVSDiodes:PUSB3F96X_PASS")
		(at 132.08 166.37 0)
		(unit 1)
		(exclude_from_sim no)
		(in_bom yes)
		(on_board yes)
		(dnp no)
		(fields_autoplaced yes)
		(property "Reference" "D801"
			(at 146.05 168.9099 0)
			(effects
				(font
					(size 1.27 1.27)
					(thickness 0.15)
				)
				(justify left)
			)
		)
		(property "Value" "PUSB3F96X_PASS"
			(at 157.48 173.99 0)
			(effects
				(font
					(size 1.27 1.27)
					(thickness 0.15)
				)
				(justify left bottom)
				(hide yes)
			)
		)
		(property "Footprint" "antmicro-footprints:Nexperia_DFN-10_2.5x1mm_P0.5mm"
			(at 157.48 176.53 0)
			(effects
				(font
					(size 1.27 1.27)
					(thickness 0.15)
				)
				(justify left bottom)
				(hide yes)
			)
		)
		(property "Datasheet" "https://mouser.com/datasheet/2/916/PUSB3F96-1600324.pdf"
			(at 157.48 179.07 0)
			(effects
				(font
					(size 1.27 1.27)
					(thickness 0.15)
				)
				(justify left bottom)
				(hide yes)
			)
		)
		(property "Description" ""
			(at 132.08 166.37 0)
			(effects
				(font
					(size 1.27 1.27)
				)
				(hide yes)
			)
		)
		(property "Manufacturer" "Nexperia"
			(at 157.48 181.61 0)
			(effects
				(font
					(size 1.27 1.27)
					(thickness 0.15)
				)
				(justify left bottom)
				(hide yes)
			)
		)
		(property "MPN" "PUSB3F96X"
			(at 146.05 171.4499 0)
			(effects
				(font
					(size 1.27 1.27)
					(thickness 0.15)
				)
				(justify left)
			)
		)
		(property "Author" "Antmicro"
			(at 157.48 184.15 0)
			(effects
				(font
					(size 1.27 1.27)
					(thickness 0.15)
				)
				(justify left bottom)
				(hide yes)
			)
		)
		(property "License" "Apache-2.0"
			(at 157.48 186.69 0)
			(effects
				(font
					(size 1.27 1.27)
					(thickness 0.15)
				)
				(justify left bottom)
				(hide yes)
			)
		)
		(pin "1"
		)
		(pin "10"
		)
		(pin "2"
		)
		(pin "3"
		)
		(pin "4"
		)
		(pin "5"
		)
		(pin "6"
		)
		(pin "7"
		)
		(pin "8"
		)
		(pin "9"
		)
		(instances
			(project "cm4-baseboard"
				(path ""
					(reference "D801")
					(unit 1)
				)
			)
		)
	)
	(symbol
		(lib_id "antmicropower:+5V")
		(at 181.61 163.83 0)
		(unit 1)
		(exclude_from_sim no)
		(in_bom yes)
		(on_board yes)
		(dnp no)
		(property "Reference" "#PWR0818"
			(at 196.85 166.37 0)
			(effects
				(font
					(size 1.27 1.27)
					(thickness 0.15)
				)
				(justify left bottom)
				(hide yes)
			)
		)
		(property "Value" "+5V"
			(at 181.61 158.75 0)
			(effects
				(font
					(size 1.27 1.27)
					(thickness 0.15)
				)
			)
		)
		(property "Footprint" ""
			(at 196.85 171.45 0)
			(effects
				(font
					(size 1.27 1.27)
					(thickness 0.15)
				)
				(justify left bottom)
				(hide yes)
			)
		)
		(property "Datasheet" ""
			(at 196.85 173.99 0)
			(effects
				(font
					(size 1.27 1.27)
					(thickness 0.15)
				)
				(justify left bottom)
				(hide yes)
			)
		)
		(property "Description" ""
			(at 181.61 163.83 0)
			(effects
				(font
					(size 1.27 1.27)
				)
				(hide yes)
			)
		)
		(property "Author" "Antmicro"
			(at 196.85 171.45 0)
			(effects
				(font
					(size 1.27 1.27)
					(thickness 0.15)
				)
				(justify left bottom)
				(hide yes)
			)
		)
		(property "License" "Apache-2.0"
			(at 196.85 173.99 0)
			(effects
				(font
					(size 1.27 1.27)
					(thickness 0.15)
				)
				(justify left bottom)
				(hide yes)
			)
		)
		(pin "1"
		)
		(instances
			(project "cm4-baseboard"
				(path ""
					(reference "#PWR0818")
					(unit 1)
				)
			)
		)
	)
	(symbol
		(lib_id "antmicroCapacitors0402:C_10p_0402")
		(at 309.88 165.1 90)
		(unit 1)
		(exclude_from_sim no)
		(in_bom yes)
		(on_board yes)
		(dnp no)
		(fields_autoplaced yes)
		(property "Reference" "C810"
			(at 307.34 161.2835 90)
			(effects
				(font
					(size 1.27 1.27)
					(thickness 0.15)
				)
				(justify left)
			)
		)
		(property "Value" "C_10p_0402"
			(at 320.04 144.78 0)
			(effects
				(font
					(size 1.27 1.27)
					(thickness 0.15)
				)
				(justify left bottom)
				(hide yes)
			)
		)
		(property "Footprint" "antmicro-footprints:C_0402_1005Metric"
			(at 322.58 144.78 0)
			(effects
				(font
					(size 1.27 1.27)
					(thickness 0.15)
				)
				(justify left bottom)
				(hide yes)
			)
		)
		(property "Datasheet" "https://www.murata.com/products/productdetail?partno=GCM1555C1H100GA16%23"
			(at 325.12 144.78 0)
			(effects
				(font
					(size 1.27 1.27)
					(thickness 0.15)
				)
				(justify left bottom)
				(hide yes)
			)
		)
		(property "Description" ""
			(at 309.88 165.1 0)
			(effects
				(font
					(size 1.27 1.27)
				)
				(hide yes)
			)
		)
		(property "MPN" "GCM1555C1H100GA16D"
			(at 327.66 144.78 0)
			(effects
				(font
					(size 1.27 1.27)
					(thickness 0.15)
				)
				(justify left bottom)
				(hide yes)
			)
		)
		(property "Manufacturer" "Murata"
			(at 330.2 144.78 0)
			(effects
				(font
					(size 1.27 1.27)
					(thickness 0.15)
				)
				(justify left bottom)
				(hide yes)
			)
		)
		(property "License" "Apache-2.0"
			(at 332.74 144.78 0)
			(effects
				(font
					(size 1.27 1.27)
					(thickness 0.15)
				)
				(justify left bottom)
				(hide yes)
			)
		)
		(property "Author" "Antmicro"
			(at 335.28 144.78 0)
			(effects
				(font
					(size 1.27 1.27)
					(thickness 0.15)
				)
				(justify left bottom)
				(hide yes)
			)
		)
		(property "Val" "10p"
			(at 307.34 163.8235 90)
			(effects
				(font
					(size 1.27 1.27)
					(thickness 0.15)
				)
				(justify left)
			)
		)
		(property "Voltage" "50V"
			(at 337.82 144.78 0)
			(effects
				(font
					(size 1.27 1.27)
				)
				(justify left bottom)
				(hide yes)
			)
		)
		(property "Dielectric" "C0G"
			(at 340.36 144.78 0)
			(effects
				(font
					(size 1.27 1.27)
				)
				(justify left bottom)
				(hide yes)
			)
		)
		(pin "1"
		)
		(pin "2"
		)
		(instances
			(project "cm4-baseboard"
				(path ""
					(reference "C810")
					(unit 1)
				)
			)
		)
	)
	(symbol
		(lib_id "antmicroCapacitors0402:C_100n_0402")
		(at 273.05 149.86 180)
		(unit 1)
		(exclude_from_sim no)
		(in_bom yes)
		(on_board yes)
		(dnp no)
		(property "Reference" "C809"
			(at 266.7 148.59 0)
			(effects
				(font
					(size 1.27 1.27)
					(thickness 0.15)
				)
			)
		)
		(property "Value" "C_100n_0402"
			(at 252.73 139.7 0)
			(effects
				(font
					(size 1.27 1.27)
					(thickness 0.15)
				)
				(justify left bottom)
				(hide yes)
			)
		)
		(property "Footprint" "antmicro-footprints:C_0402_1005Metric"
			(at 252.73 137.16 0)
			(effects
				(font
					(size 1.27 1.27)
					(thickness 0.15)
				)
				(justify left bottom)
				(hide yes)
			)
		)
		(property "Datasheet" "https://www.murata.com/products/productdetail?partno=GRM155R61H104KE14%23"
			(at 252.73 134.62 0)
			(effects
				(font
					(size 1.27 1.27)
					(thickness 0.15)
				)
				(justify left bottom)
				(hide yes)
			)
		)
		(property "Description" ""
			(at 273.05 149.86 0)
			(effects
				(font
					(size 1.27 1.27)
				)
				(hide yes)
			)
		)
		(property "MPN" "GRM155R61H104KE14D"
			(at 252.73 132.08 0)
			(effects
				(font
					(size 1.27 1.27)
					(thickness 0.15)
				)
				(justify left bottom)
				(hide yes)
			)
		)
		(property "Manufacturer" "Murata"
			(at 252.73 129.54 0)
			(effects
				(font
					(size 1.27 1.27)
					(thickness 0.15)
				)
				(justify left bottom)
				(hide yes)
			)
		)
		(property "License" "Apache-2.0"
			(at 252.73 127 0)
			(effects
				(font
					(size 1.27 1.27)
					(thickness 0.15)
				)
				(justify left bottom)
				(hide yes)
			)
		)
		(property "Author" "Antmicro"
			(at 252.73 124.46 0)
			(effects
				(font
					(size 1.27 1.27)
					(thickness 0.15)
				)
				(justify left bottom)
				(hide yes)
			)
		)
		(property "Val" "100n"
			(at 271.78 148.59 0)
			(effects
				(font
					(size 1.27 1.27)
					(thickness 0.15)
				)
				(justify right)
			)
		)
		(property "Voltage" "50V"
			(at 252.73 121.92 0)
			(effects
				(font
					(size 1.27 1.27)
				)
				(justify left bottom)
				(hide yes)
			)
		)
		(property "Dielectric" "X5R"
			(at 252.73 119.38 0)
			(effects
				(font
					(size 1.27 1.27)
				)
				(justify left bottom)
				(hide yes)
			)
		)
		(pin "1"
		)
		(pin "2"
		)
		(instances
			(project "cm4-baseboard"
				(path ""
					(reference "C809")
					(unit 1)
				)
			)
		)
	)
	(symbol
		(lib_id "antmicropower:+5V")
		(at 58.42 177.8 0)
		(unit 1)
		(exclude_from_sim no)
		(in_bom yes)
		(on_board yes)
		(dnp no)
		(property "Reference" "#PWR0803"
			(at 73.66 180.34 0)
			(effects
				(font
					(size 1.27 1.27)
					(thickness 0.15)
				)
				(justify left bottom)
				(hide yes)
			)
		)
		(property "Value" "+5V"
			(at 58.42 172.72 0)
			(effects
				(font
					(size 1.27 1.27)
					(thickness 0.15)
				)
			)
		)
		(property "Footprint" ""
			(at 73.66 185.42 0)
			(effects
				(font
					(size 1.27 1.27)
					(thickness 0.15)
				)
				(justify left bottom)
				(hide yes)
			)
		)
		(property "Datasheet" ""
			(at 73.66 187.96 0)
			(effects
				(font
					(size 1.27 1.27)
					(thickness 0.15)
				)
				(justify left bottom)
				(hide yes)
			)
		)
		(property "Description" ""
			(at 58.42 177.8 0)
			(effects
				(font
					(size 1.27 1.27)
				)
				(hide yes)
			)
		)
		(property "Author" "Antmicro"
			(at 73.66 185.42 0)
			(effects
				(font
					(size 1.27 1.27)
					(thickness 0.15)
				)
				(justify left bottom)
				(hide yes)
			)
		)
		(property "License" "Apache-2.0"
			(at 73.66 187.96 0)
			(effects
				(font
					(size 1.27 1.27)
					(thickness 0.15)
				)
				(justify left bottom)
				(hide yes)
			)
		)
		(pin "1"
		)
		(instances
			(project "cm4-baseboard"
				(path ""
					(reference "#PWR0803")
					(unit 1)
				)
			)
		)
	)
	(symbol
		(lib_id "antmicroWire2BoardConnectors:JST_SH_1x2_SM02B-SRSS-TB-LF-SN")
		(at 375.92 116.84 0)
		(mirror x)
		(unit 1)
		(exclude_from_sim no)
		(in_bom yes)
		(on_board yes)
		(dnp no)
		(property "Reference" "J804"
			(at 382.27 110.49 0)
			(effects
				(font
					(size 1.27 1.27)
					(thickness 0.15)
				)
				(justify left)
			)
		)
		(property "Value" "JST_SH_1x2_SM02B-SRSS-TB-LF-SN"
			(at 402.59 110.49 0)
			(effects
				(font
					(size 1.27 1.27)
					(thickness 0.15)
				)
				(justify left bottom)
				(hide yes)
			)
		)
		(property "Footprint" "antmicro-footprints:Conn_JST_SH_1x2_SM02B-SRSS-TB-LF-SN"
			(at 402.59 107.95 0)
			(effects
				(font
					(size 1.27 1.27)
					(thickness 0.15)
				)
				(justify left bottom)
				(hide yes)
			)
		)
		(property "Datasheet" "https://www.jst-mfg.com/product/pdf/eng/eSH.pdf"
			(at 402.59 105.41 0)
			(effects
				(font
					(size 1.27 1.27)
					(thickness 0.15)
				)
				(justify left bottom)
				(hide yes)
			)
		)
		(property "Description" ""
			(at 375.92 116.84 0)
			(effects
				(font
					(size 1.27 1.27)
				)
				(hide yes)
			)
		)
		(property "MPN" "SM02B-SRSS-TB(LF)(SN)"
			(at 382.27 113.03 0)
			(effects
				(font
					(size 1.27 1.27)
					(thickness 0.15)
				)
				(justify left)
			)
		)
		(property "Manufacturer" "JST Automotive Connectors"
			(at 402.59 100.33 0)
			(effects
				(font
					(size 1.27 1.27)
					(thickness 0.15)
				)
				(justify left bottom)
				(hide yes)
			)
		)
		(property "Author" "Antmicro"
			(at 402.59 97.79 0)
			(effects
				(font
					(size 1.27 1.27)
					(thickness 0.15)
				)
				(justify left bottom)
				(hide yes)
			)
		)
		(property "License" "Apache-2.0"
			(at 402.59 95.25 0)
			(effects
				(font
					(size 1.27 1.27)
					(thickness 0.15)
				)
				(justify left bottom)
				(hide yes)
			)
		)
		(pin "MP"
		)
		(pin "1"
		)
		(pin "2"
		)
		(instances
			(project "cm4-baseboard"
				(path ""
					(reference "J804")
					(unit 1)
				)
			)
		)
	)
	(symbol
		(lib_id "antmicroCapacitors0402:C_template_name_0402")
		(at 360.68 121.92 90)
		(unit 1)
		(exclude_from_sim no)
		(in_bom no)
		(on_board yes)
		(dnp yes)
		(property "Reference" "C827"
			(at 362.458 119.38 90)
			(effects
				(font
					(size 1.27 1.27)
					(thickness 0.15)
				)
				(justify right)
			)
		)
		(property "Value" "C_template_name_0402"
			(at 370.84 101.6 0)
			(effects
				(font
					(size 1.27 1.27)
					(thickness 0.15)
				)
				(justify left bottom)
				(hide yes)
			)
		)
		(property "Footprint" "antmicro-footprints:C_0402_1005Metric"
			(at 373.38 101.6 0)
			(effects
				(font
					(size 1.27 1.27)
					(thickness 0.15)
				)
				(justify left bottom)
				(hide yes)
			)
		)
		(property "Datasheet" "template_datasheet"
			(at 375.92 101.6 0)
			(effects
				(font
					(size 1.27 1.27)
					(thickness 0.15)
				)
				(justify left bottom)
				(hide yes)
			)
		)
		(property "Description" ""
			(at 360.68 121.92 0)
			(effects
				(font
					(size 1.27 1.27)
				)
				(hide yes)
			)
		)
		(property "MPN" "template_MPN"
			(at 378.46 101.6 0)
			(effects
				(font
					(size 1.27 1.27)
					(thickness 0.15)
				)
				(justify left bottom)
				(hide yes)
			)
		)
		(property "Manufacturer" "template_manufacturer"
			(at 381 101.6 0)
			(effects
				(font
					(size 1.27 1.27)
					(thickness 0.15)
				)
				(justify left bottom)
				(hide yes)
			)
		)
		(property "License" "Apache-2.0"
			(at 383.54 101.6 0)
			(effects
				(font
					(size 1.27 1.27)
					(thickness 0.15)
				)
				(justify left bottom)
				(hide yes)
			)
		)
		(property "Author" "Antmicro"
			(at 386.08 101.6 0)
			(effects
				(font
					(size 1.27 1.27)
					(thickness 0.15)
				)
				(justify left bottom)
				(hide yes)
			)
		)
		(property "Val" "template_value"
			(at 356.87 119.3737 0)
			(effects
				(font
					(size 1.27 1.27)
					(thickness 0.15)
				)
				(hide yes)
			)
		)
		(property "Voltage" "template_voltage"
			(at 388.62 101.6 0)
			(effects
				(font
					(size 1.27 1.27)
				)
				(justify left bottom)
				(hide yes)
			)
		)
		(property "Dielectric" "template_dielectric"
			(at 391.16 101.6 0)
			(effects
				(font
					(size 1.27 1.27)
				)
				(justify left bottom)
				(hide yes)
			)
		)
		(pin "1"
		)
		(pin "2"
		)
		(instances
			(project "cm4-baseboard"
				(path ""
					(reference "C827")
					(unit 1)
				)
			)
		)
	)
	(symbol
		(lib_id "antmicroResistors0402:R_10k_0402")
		(at 243.84 120.65 90)
		(unit 1)
		(exclude_from_sim no)
		(in_bom no)
		(on_board yes)
		(dnp yes)
		(property "Reference" "R805"
			(at 245.11 116.84 90)
			(effects
				(font
					(size 1.27 1.27)
					(thickness 0.15)
				)
				(justify right)
			)
		)
		(property "Value" "R_10k_0402"
			(at 256.54 100.33 0)
			(effects
				(font
					(size 1.27 1.27)
					(thickness 0.15)
				)
				(justify left bottom)
				(hide yes)
			)
		)
		(property "Footprint" "antmicro-footprints:R_0402_1005Metric"
			(at 259.08 100.33 0)
			(effects
				(font
					(size 1.27 1.27)
					(thickness 0.15)
				)
				(justify left bottom)
				(hide yes)
			)
		)
		(property "Datasheet" "https://www.bourns.com/docs/product-datasheets/cr.pdf"
			(at 261.62 100.33 0)
			(effects
				(font
					(size 1.27 1.27)
					(thickness 0.15)
				)
				(justify left bottom)
				(hide yes)
			)
		)
		(property "Description" ""
			(at 243.84 120.65 0)
			(effects
				(font
					(size 1.27 1.27)
				)
				(hide yes)
			)
		)
		(property "MPN" "CR0402-FX-1002GLF"
			(at 264.16 100.33 0)
			(effects
				(font
					(size 1.27 1.27)
					(thickness 0.15)
				)
				(justify left bottom)
				(hide yes)
			)
		)
		(property "Manufacturer" "Bourns"
			(at 266.7 100.33 0)
			(effects
				(font
					(size 1.27 1.27)
					(thickness 0.15)
				)
				(justify left bottom)
				(hide yes)
			)
		)
		(property "License" "Apache-2.0"
			(at 269.24 100.33 0)
			(effects
				(font
					(size 1.27 1.27)
					(thickness 0.15)
				)
				(justify left bottom)
				(hide yes)
			)
		)
		(property "Author" "Antmicro"
			(at 271.78 100.33 0)
			(effects
				(font
					(size 1.27 1.27)
					(thickness 0.15)
				)
				(justify left bottom)
				(hide yes)
			)
		)
		(property "Val" "10k"
			(at 245.11 119.38 90)
			(effects
				(font
					(size 1.27 1.27)
					(thickness 0.15)
				)
				(justify right)
			)
		)
		(property "Tolerance" "1%"
			(at 254 100.33 0)
			(effects
				(font
					(size 1.27 1.27)
				)
				(justify left bottom)
				(hide yes)
			)
		)
		(pin "1"
		)
		(pin "2"
		)
		(instances
			(project "cm4-baseboard"
				(path ""
					(reference "R805")
					(unit 1)
				)
			)
		)
	)
	(symbol
		(lib_id "antmicroResistors0402:R_2k2_0402")
		(at 331.47 129.54 270)
		(mirror x)
		(unit 1)
		(exclude_from_sim no)
		(in_bom yes)
		(on_board yes)
		(dnp no)
		(property "Reference" "R808"
			(at 329.946 125.73 90)
			(effects
				(font
					(size 1.27 1.27)
					(thickness 0.15)
				)
				(justify right)
			)
		)
		(property "Value" "R_2k2_0402"
			(at 318.77 109.22 0)
			(effects
				(font
					(size 1.27 1.27)
					(thickness 0.15)
				)
				(justify left bottom)
				(hide yes)
			)
		)
		(property "Footprint" "antmicro-footprints:R_0402_1005Metric"
			(at 316.23 109.22 0)
			(effects
				(font
					(size 1.27 1.27)
					(thickness 0.15)
				)
				(justify left bottom)
				(hide yes)
			)
		)
		(property "Datasheet" "https://www.bourns.com/docs/product-datasheets/cr.pdf"
			(at 313.69 109.22 0)
			(effects
				(font
					(size 1.27 1.27)
					(thickness 0.15)
				)
				(justify left bottom)
				(hide yes)
			)
		)
		(property "Description" "SMD Chip Resistor, 2.2 kohm, ± 1%, 62.5 mW, 0402 [1005 Metric], Thick Film, General Purpose"
			(at 300.99 109.22 0)
			(effects
				(font
					(size 1.27 1.27)
				)
				(justify left bottom)
				(hide yes)
			)
		)
		(property "MPN" "CR0402-FX-2201GLF"
			(at 311.15 109.22 0)
			(effects
				(font
					(size 1.27 1.27)
					(thickness 0.15)
				)
				(justify left bottom)
				(hide yes)
			)
		)
		(property "Manufacturer" "Bourns"
			(at 308.61 109.22 0)
			(effects
				(font
					(size 1.27 1.27)
					(thickness 0.15)
				)
				(justify left bottom)
				(hide yes)
			)
		)
		(property "License" "Apache-2.0"
			(at 306.07 109.22 0)
			(effects
				(font
					(size 1.27 1.27)
					(thickness 0.15)
				)
				(justify left bottom)
				(hide yes)
			)
		)
		(property "Author" "Antmicro"
			(at 303.53 109.22 0)
			(effects
				(font
					(size 1.27 1.27)
					(thickness 0.15)
				)
				(justify left bottom)
				(hide yes)
			)
		)
		(property "Val" "2k2"
			(at 329.946 128.27 90)
			(effects
				(font
					(size 1.27 1.27)
					(thickness 0.15)
				)
				(justify right)
			)
		)
		(property "Tolerance" "1%"
			(at 321.31 109.22 0)
			(effects
				(font
					(size 1.27 1.27)
				)
				(justify left bottom)
				(hide yes)
			)
		)
		(pin "2"
		)
		(pin "1"
		)
		(instances
			(project "cm4-baseboard"
				(path ""
					(reference "R808")
					(unit 1)
				)
			)
		)
	)
	(symbol
		(lib_id "antmicroTVSDiodes:PUSB3F96X_PASS")
		(at 182.88 167.64 0)
		(unit 1)
		(exclude_from_sim no)
		(in_bom yes)
		(on_board yes)
		(dnp no)
		(fields_autoplaced yes)
		(property "Reference" "D807"
			(at 196.85 170.1799 0)
			(effects
				(font
					(size 1.27 1.27)
					(thickness 0.15)
				)
				(justify left)
			)
		)
		(property "Value" "PUSB3F96X_PASS"
			(at 208.28 175.26 0)
			(effects
				(font
					(size 1.27 1.27)
					(thickness 0.15)
				)
				(justify left bottom)
				(hide yes)
			)
		)
		(property "Footprint" "antmicro-footprints:Nexperia_DFN-10_2.5x1mm_P0.5mm"
			(at 208.28 177.8 0)
			(effects
				(font
					(size 1.27 1.27)
					(thickness 0.15)
				)
				(justify left bottom)
				(hide yes)
			)
		)
		(property "Datasheet" "https://mouser.com/datasheet/2/916/PUSB3F96-1600324.pdf"
			(at 208.28 180.34 0)
			(effects
				(font
					(size 1.27 1.27)
					(thickness 0.15)
				)
				(justify left bottom)
				(hide yes)
			)
		)
		(property "Description" ""
			(at 182.88 167.64 0)
			(effects
				(font
					(size 1.27 1.27)
				)
				(hide yes)
			)
		)
		(property "Manufacturer" "Nexperia"
			(at 208.28 182.88 0)
			(effects
				(font
					(size 1.27 1.27)
					(thickness 0.15)
				)
				(justify left bottom)
				(hide yes)
			)
		)
		(property "MPN" "PUSB3F96X"
			(at 196.85 172.7199 0)
			(effects
				(font
					(size 1.27 1.27)
					(thickness 0.15)
				)
				(justify left)
			)
		)
		(property "Author" "Antmicro"
			(at 208.28 185.42 0)
			(effects
				(font
					(size 1.27 1.27)
					(thickness 0.15)
				)
				(justify left bottom)
				(hide yes)
			)
		)
		(property "License" "Apache-2.0"
			(at 208.28 187.96 0)
			(effects
				(font
					(size 1.27 1.27)
					(thickness 0.15)
				)
				(justify left bottom)
				(hide yes)
			)
		)
		(pin "1"
		)
		(pin "10"
		)
		(pin "2"
		)
		(pin "3"
		)
		(pin "4"
		)
		(pin "5"
		)
		(pin "6"
		)
		(pin "7"
		)
		(pin "8"
		)
		(pin "9"
		)
		(instances
			(project "cm4-baseboard"
				(path ""
					(reference "D807")
					(unit 1)
				)
			)
		)
	)
	(symbol
		(lib_id "antmicropower:GND")
		(at 314.96 167.64 0)
		(unit 1)
		(exclude_from_sim no)
		(in_bom yes)
		(on_board yes)
		(dnp no)
		(property "Reference" "#PWR0834"
			(at 323.85 170.18 0)
			(effects
				(font
					(size 1.27 1.27)
					(thickness 0.15)
				)
				(justify left bottom)
				(hide yes)
			)
		)
		(property "Value" "GND"
			(at 314.96 171.45 0)
			(effects
				(font
					(size 1.27 1.27)
					(thickness 0.15)
				)
			)
		)
		(property "Footprint" ""
			(at 323.85 175.26 0)
			(effects
				(font
					(size 1.27 1.27)
					(thickness 0.15)
				)
				(justify left bottom)
				(hide yes)
			)
		)
		(property "Datasheet" ""
			(at 323.85 180.34 0)
			(effects
				(font
					(size 1.27 1.27)
					(thickness 0.15)
				)
				(justify left bottom)
				(hide yes)
			)
		)
		(property "Description" ""
			(at 314.96 167.64 0)
			(effects
				(font
					(size 1.27 1.27)
				)
				(hide yes)
			)
		)
		(property "Author" "Antmicro"
			(at 323.85 175.26 0)
			(effects
				(font
					(size 1.27 1.27)
					(thickness 0.15)
				)
				(justify left bottom)
				(hide yes)
			)
		)
		(property "License" "Apache-2.0"
			(at 323.85 177.8 0)
			(effects
				(font
					(size 1.27 1.27)
					(thickness 0.15)
				)
				(justify left bottom)
				(hide yes)
			)
		)
		(pin "1"
		)
		(instances
			(project "cm4-baseboard"
				(path ""
					(reference "#PWR0834")
					(unit 1)
				)
			)
		)
	)
	(symbol
		(lib_id "antmicroTVSDiodes:PUSB3F96X_PASS")
		(at 182.88 226.06 0)
		(unit 1)
		(exclude_from_sim no)
		(in_bom yes)
		(on_board yes)
		(dnp no)
		(fields_autoplaced yes)
		(property "Reference" "D810"
			(at 196.85 228.5999 0)
			(effects
				(font
					(size 1.27 1.27)
					(thickness 0.15)
				)
				(justify left)
			)
		)
		(property "Value" "PUSB3F96X_PASS"
			(at 208.28 233.68 0)
			(effects
				(font
					(size 1.27 1.27)
					(thickness 0.15)
				)
				(justify left bottom)
				(hide yes)
			)
		)
		(property "Footprint" "antmicro-footprints:Nexperia_DFN-10_2.5x1mm_P0.5mm"
			(at 208.28 236.22 0)
			(effects
				(font
					(size 1.27 1.27)
					(thickness 0.15)
				)
				(justify left bottom)
				(hide yes)
			)
		)
		(property "Datasheet" "https://mouser.com/datasheet/2/916/PUSB3F96-1600324.pdf"
			(at 208.28 238.76 0)
			(effects
				(font
					(size 1.27 1.27)
					(thickness 0.15)
				)
				(justify left bottom)
				(hide yes)
			)
		)
		(property "Description" ""
			(at 182.88 226.06 0)
			(effects
				(font
					(size 1.27 1.27)
				)
				(hide yes)
			)
		)
		(property "Manufacturer" "Nexperia"
			(at 208.28 241.3 0)
			(effects
				(font
					(size 1.27 1.27)
					(thickness 0.15)
				)
				(justify left bottom)
				(hide yes)
			)
		)
		(property "MPN" "PUSB3F96X"
			(at 196.85 231.1399 0)
			(effects
				(font
					(size 1.27 1.27)
					(thickness 0.15)
				)
				(justify left)
			)
		)
		(property "Author" "Antmicro"
			(at 208.28 243.84 0)
			(effects
				(font
					(size 1.27 1.27)
					(thickness 0.15)
				)
				(justify left bottom)
				(hide yes)
			)
		)
		(property "License" "Apache-2.0"
			(at 208.28 246.38 0)
			(effects
				(font
					(size 1.27 1.27)
					(thickness 0.15)
				)
				(justify left bottom)
				(hide yes)
			)
		)
		(pin "1"
		)
		(pin "10"
		)
		(pin "2"
		)
		(pin "3"
		)
		(pin "4"
		)
		(pin "5"
		)
		(pin "6"
		)
		(pin "7"
		)
		(pin "8"
		)
		(pin "9"
		)
		(instances
			(project "cm4-baseboard"
				(path ""
					(reference "D810")
					(unit 1)
				)
			)
		)
	)
	(symbol
		(lib_id "antmicropower:GND")
		(at 275.59 157.48 0)
		(unit 1)
		(exclude_from_sim no)
		(in_bom yes)
		(on_board yes)
		(dnp no)
		(property "Reference" "#PWR0833"
			(at 284.48 160.02 0)
			(effects
				(font
					(size 1.27 1.27)
					(thickness 0.15)
				)
				(justify left bottom)
				(hide yes)
			)
		)
		(property "Value" "GND"
			(at 275.59 161.29 0)
			(effects
				(font
					(size 1.27 1.27)
					(thickness 0.15)
				)
			)
		)
		(property "Footprint" ""
			(at 284.48 165.1 0)
			(effects
				(font
					(size 1.27 1.27)
					(thickness 0.15)
				)
				(justify left bottom)
				(hide yes)
			)
		)
		(property "Datasheet" ""
			(at 284.48 170.18 0)
			(effects
				(font
					(size 1.27 1.27)
					(thickness 0.15)
				)
				(justify left bottom)
				(hide yes)
			)
		)
		(property "Description" ""
			(at 275.59 157.48 0)
			(effects
				(font
					(size 1.27 1.27)
				)
				(hide yes)
			)
		)
		(property "Author" "Antmicro"
			(at 284.48 165.1 0)
			(effects
				(font
					(size 1.27 1.27)
					(thickness 0.15)
				)
				(justify left bottom)
				(hide yes)
			)
		)
		(property "License" "Apache-2.0"
			(at 284.48 167.64 0)
			(effects
				(font
					(size 1.27 1.27)
					(thickness 0.15)
				)
				(justify left bottom)
				(hide yes)
			)
		)
		(pin "1"
		)
		(instances
			(project "cm4-baseboard"
				(path ""
					(reference "#PWR0833")
					(unit 1)
				)
			)
		)
	)
	(symbol
		(lib_id "antmicroTVSDiodes:PUSB3F96X_PASS")
		(at 132.08 224.79 0)
		(unit 1)
		(exclude_from_sim no)
		(in_bom yes)
		(on_board yes)
		(dnp no)
		(fields_autoplaced yes)
		(property "Reference" "D804"
			(at 146.05 227.3299 0)
			(effects
				(font
					(size 1.27 1.27)
					(thickness 0.15)
				)
				(justify left)
			)
		)
		(property "Value" "PUSB3F96X_PASS"
			(at 157.48 232.41 0)
			(effects
				(font
					(size 1.27 1.27)
					(thickness 0.15)
				)
				(justify left bottom)
				(hide yes)
			)
		)
		(property "Footprint" "antmicro-footprints:Nexperia_DFN-10_2.5x1mm_P0.5mm"
			(at 157.48 234.95 0)
			(effects
				(font
					(size 1.27 1.27)
					(thickness 0.15)
				)
				(justify left bottom)
				(hide yes)
			)
		)
		(property "Datasheet" "https://mouser.com/datasheet/2/916/PUSB3F96-1600324.pdf"
			(at 157.48 237.49 0)
			(effects
				(font
					(size 1.27 1.27)
					(thickness 0.15)
				)
				(justify left bottom)
				(hide yes)
			)
		)
		(property "Description" ""
			(at 132.08 224.79 0)
			(effects
				(font
					(size 1.27 1.27)
				)
				(hide yes)
			)
		)
		(property "Manufacturer" "Nexperia"
			(at 157.48 240.03 0)
			(effects
				(font
					(size 1.27 1.27)
					(thickness 0.15)
				)
				(justify left bottom)
				(hide yes)
			)
		)
		(property "MPN" "PUSB3F96X"
			(at 146.05 229.8699 0)
			(effects
				(font
					(size 1.27 1.27)
					(thickness 0.15)
				)
				(justify left)
			)
		)
		(property "Author" "Antmicro"
			(at 157.48 242.57 0)
			(effects
				(font
					(size 1.27 1.27)
					(thickness 0.15)
				)
				(justify left bottom)
				(hide yes)
			)
		)
		(property "License" "Apache-2.0"
			(at 157.48 245.11 0)
			(effects
				(font
					(size 1.27 1.27)
					(thickness 0.15)
				)
				(justify left bottom)
				(hide yes)
			)
		)
		(pin "1"
		)
		(pin "10"
		)
		(pin "2"
		)
		(pin "3"
		)
		(pin "4"
		)
		(pin "5"
		)
		(pin "6"
		)
		(pin "7"
		)
		(pin "8"
		)
		(pin "9"
		)
		(instances
			(project "cm4-baseboard"
				(path ""
					(reference "D804")
					(unit 1)
				)
			)
		)
	)
	(symbol
		(lib_id "antmicroWire2BoardConnectors:JST_SH_1x4_SM04B-SRSS-TB-LF-SN")
		(at 109.22 50.8 0)
		(mirror x)
		(unit 1)
		(exclude_from_sim no)
		(in_bom yes)
		(on_board yes)
		(dnp no)
		(fields_autoplaced yes)
		(property "Reference" "J802"
			(at 114.3 31.75 0)
			(effects
				(font
					(size 1.27 1.27)
					(thickness 0.15)
				)
			)
		)
		(property "Value" "JST_SH_1x4_SM04B-SRSS-TB-LF-SN"
			(at 135.89 43.18 0)
			(effects
				(font
					(size 1.27 1.27)
					(thickness 0.15)
				)
				(justify left bottom)
				(hide yes)
			)
		)
		(property "Footprint" "antmicro-footprints:Conn_JST_SH_1x4_SM04B-SRSS-TB-LF-SN"
			(at 135.89 40.64 0)
			(effects
				(font
					(size 1.27 1.27)
					(thickness 0.15)
				)
				(justify left bottom)
				(hide yes)
			)
		)
		(property "Datasheet" "https://www.jst-mfg.com/product/pdf/eng/eSH.pdf"
			(at 135.89 38.1 0)
			(effects
				(font
					(size 1.27 1.27)
					(thickness 0.15)
				)
				(justify left bottom)
				(hide yes)
			)
		)
		(property "Description" ""
			(at 109.22 50.8 0)
			(effects
				(font
					(size 1.27 1.27)
				)
				(hide yes)
			)
		)
		(property "MPN" "SM04B-SRSS-TB(LF)(SN)"
			(at 114.3 34.29 0)
			(effects
				(font
					(size 1.27 1.27)
					(thickness 0.15)
				)
			)
		)
		(property "Manufacturer" "JST Automotive Connectors"
			(at 135.89 35.56 0)
			(effects
				(font
					(size 1.27 1.27)
					(thickness 0.15)
				)
				(justify left bottom)
				(hide yes)
			)
		)
		(property "Author" "Antmicro"
			(at 135.89 33.02 0)
			(effects
				(font
					(size 1.27 1.27)
					(thickness 0.15)
				)
				(justify left bottom)
				(hide yes)
			)
		)
		(property "License" "Apache-2.0"
			(at 135.89 30.48 0)
			(effects
				(font
					(size 1.27 1.27)
					(thickness 0.15)
				)
				(justify left bottom)
				(hide yes)
			)
		)
		(pin "1"
		)
		(pin "2"
		)
		(pin "3"
		)
		(pin "4"
		)
		(pin "MP"
		)
		(instances
			(project "cm4-baseboard"
				(path ""
					(reference "J802")
					(unit 1)
				)
			)
		)
	)
	(symbol
		(lib_id "antmicroB2BConnectors:Socket_Samtec_ERF5_2x20_ERF5-020-05.0-L-DV-K-TR")
		(at 44.45 179.07 0)
		(unit 1)
		(exclude_from_sim no)
		(in_bom yes)
		(on_board yes)
		(dnp no)
		(property "Reference" "J801"
			(at 50.8 234.95 0)
			(effects
				(font
					(size 1.27 1.27)
					(thickness 0.15)
				)
			)
		)
		(property "Value" "Socket_Samtec_ERF5_2x20_ERF5-020-05.0-L-DV-K-TR"
			(at 71.12 184.15 0)
			(effects
				(font
					(size 1.27 1.27)
					(thickness 0.15)
				)
				(justify left bottom)
				(hide yes)
			)
		)
		(property "Footprint" "antmicro-footprints:Conn_Socket_Samtec_ERF5_2x20_ERF5-020-05.0-L-DV-K-TR"
			(at 71.12 186.69 0)
			(effects
				(font
					(size 1.27 1.27)
					(thickness 0.15)
				)
				(justify left bottom)
				(hide yes)
			)
		)
		(property "Datasheet" "https://suddendocs.samtec.com/productspecs/erm5-erf5.pdf?_gl=1*1g914su*_ga*MTE0MzExNjY4MC4xNjcyMTQ5NTUz*_ga_3KFNZC07WW*MTY3Mjg0NzY5Ny42LjEuMTY3Mjg0ODE3MS42MC4wLjA."
			(at 71.12 189.23 0)
			(effects
				(font
					(size 1.27 1.27)
					(thickness 0.15)
				)
				(justify left bottom)
				(hide yes)
			)
		)
		(property "Description" ""
			(at 44.45 179.07 0)
			(effects
				(font
					(size 1.27 1.27)
				)
				(hide yes)
			)
		)
		(property "MPN" "ERF5-020-05.0-L-DV-K-TR"
			(at 50.8 237.49 0)
			(effects
				(font
					(size 1.27 1.27)
					(thickness 0.15)
				)
			)
		)
		(property "Manufacturer" "Samtec"
			(at 71.12 191.77 0)
			(effects
				(font
					(size 1.27 1.27)
					(thickness 0.15)
				)
				(justify left bottom)
				(hide yes)
			)
		)
		(property "Author" "Antmicro"
			(at 71.12 196.85 0)
			(effects
				(font
					(size 1.27 1.27)
					(thickness 0.15)
				)
				(justify left bottom)
				(hide yes)
			)
		)
		(property "License" "Apache-2.0"
			(at 71.12 199.39 0)
			(effects
				(font
					(size 1.27 1.27)
					(thickness 0.15)
				)
				(justify left bottom)
				(hide yes)
			)
		)
		(property "Pitch" "0.5 mm"
			(at 71.12 194.31 0)
			(effects
				(font
					(size 1.27 1.27)
				)
				(justify left bottom)
				(hide yes)
			)
		)
		(pin "1"
		)
		(pin "10"
		)
		(pin "11"
		)
		(pin "12"
		)
		(pin "13"
		)
		(pin "14"
		)
		(pin "15"
		)
		(pin "16"
		)
		(pin "17"
		)
		(pin "18"
		)
		(pin "19"
		)
		(pin "2"
		)
		(pin "20"
		)
		(pin "21"
		)
		(pin "22"
		)
		(pin "23"
		)
		(pin "24"
		)
		(pin "25"
		)
		(pin "26"
		)
		(pin "27"
		)
		(pin "28"
		)
		(pin "29"
		)
		(pin "3"
		)
		(pin "30"
		)
		(pin "31"
		)
		(pin "32"
		)
		(pin "33"
		)
		(pin "34"
		)
		(pin "35"
		)
		(pin "36"
		)
		(pin "37"
		)
		(pin "38"
		)
		(pin "39"
		)
		(pin "4"
		)
		(pin "40"
		)
		(pin "5"
		)
		(pin "6"
		)
		(pin "7"
		)
		(pin "8"
		)
		(pin "9"
		)
		(instances
			(project "cm4-baseboard"
				(path ""
					(reference "J801")
					(unit 1)
				)
			)
		)
	)
	(symbol
		(lib_id "antmicropower:GND")
		(at 300.99 237.49 0)
		(unit 1)
		(exclude_from_sim no)
		(in_bom yes)
		(on_board yes)
		(dnp no)
		(property "Reference" "#PWR043"
			(at 309.88 240.03 0)
			(effects
				(font
					(size 1.27 1.27)
					(thickness 0.15)
				)
				(justify left bottom)
				(hide yes)
			)
		)
		(property "Value" "GND"
			(at 300.99 241.3 0)
			(effects
				(font
					(size 1.27 1.27)
				)
			)
		)
		(property "Footprint" ""
			(at 309.88 245.11 0)
			(effects
				(font
					(size 1.27 1.27)
					(thickness 0.15)
				)
				(justify left bottom)
				(hide yes)
			)
		)
		(property "Datasheet" ""
			(at 309.88 250.19 0)
			(effects
				(font
					(size 1.27 1.27)
					(thickness 0.15)
				)
				(justify left bottom)
				(hide yes)
			)
		)
		(property "Description" ""
			(at 300.99 237.49 0)
			(effects
				(font
					(size 1.27 1.27)
				)
				(hide yes)
			)
		)
		(property "Author" "Antmicro"
			(at 309.88 245.11 0)
			(effects
				(font
					(size 1.27 1.27)
					(thickness 0.15)
				)
				(justify left bottom)
				(hide yes)
			)
		)
		(property "License" "Apache-2.0"
			(at 309.88 247.65 0)
			(effects
				(font
					(size 1.27 1.27)
					(thickness 0.15)
				)
				(justify left bottom)
				(hide yes)
			)
		)
		(pin "1"
		)
		(instances
			(project "cm4-baseboard"
				(path ""
					(reference "#PWR043")
					(unit 1)
				)
			)
		)
	)
	(symbol
		(lib_id "antmicropower:GND")
		(at 181.61 237.49 0)
		(unit 1)
		(exclude_from_sim no)
		(in_bom yes)
		(on_board yes)
		(dnp no)
		(fields_autoplaced yes)
		(property "Reference" "#PWR0822"
			(at 190.5 240.03 0)
			(effects
				(font
					(size 1.27 1.27)
					(thickness 0.15)
				)
				(justify left bottom)
				(hide yes)
			)
		)
		(property "Value" "GND"
			(at 181.61 242.57 0)
			(effects
				(font
					(size 1.27 1.27)
				)
			)
		)
		(property "Footprint" ""
			(at 190.5 245.11 0)
			(effects
				(font
					(size 1.27 1.27)
					(thickness 0.15)
				)
				(justify left bottom)
				(hide yes)
			)
		)
		(property "Datasheet" ""
			(at 190.5 250.19 0)
			(effects
				(font
					(size 1.27 1.27)
					(thickness 0.15)
				)
				(justify left bottom)
				(hide yes)
			)
		)
		(property "Description" ""
			(at 181.61 237.49 0)
			(effects
				(font
					(size 1.27 1.27)
				)
				(hide yes)
			)
		)
		(property "Author" "Antmicro"
			(at 190.5 245.11 0)
			(effects
				(font
					(size 1.27 1.27)
					(thickness 0.15)
				)
				(justify left bottom)
				(hide yes)
			)
		)
		(property "License" "Apache-2.0"
			(at 190.5 247.65 0)
			(effects
				(font
					(size 1.27 1.27)
					(thickness 0.15)
				)
				(justify left bottom)
				(hide yes)
			)
		)
		(pin "1"
		)
		(instances
			(project "cm4-baseboard"
				(path ""
					(reference "#PWR0822")
					(unit 1)
				)
			)
		)
	)
	(symbol
		(lib_name "R_0R_0402_1")
		(lib_id "antmicroResistors0402:R_0R_0402")
		(at 240.03 62.23 270)
		(mirror x)
		(unit 1)
		(exclude_from_sim no)
		(in_bom yes)
		(on_board yes)
		(dnp no)
		(fields_autoplaced yes)
		(property "Reference" "R3"
			(at 242.57 58.42 90)
			(effects
				(font
					(size 1.27 1.27)
					(thickness 0.15)
				)
				(justify left)
			)
		)
		(property "Value" "R_0R_0402"
			(at 227.33 41.91 0)
			(effects
				(font
					(size 1.27 1.27)
					(thickness 0.15)
				)
				(justify left bottom)
				(hide yes)
			)
		)
		(property "Footprint" "antmicro-footprints:R_0402_1005Metric"
			(at 224.79 41.91 0)
			(effects
				(font
					(size 1.27 1.27)
					(thickness 0.15)
				)
				(justify left bottom)
				(hide yes)
			)
		)
		(property "Datasheet" "https://industrial.panasonic.com/cdbs/www-data/pdf/RDA0000/AOA0000C301.pdf"
			(at 222.25 41.91 0)
			(effects
				(font
					(size 1.27 1.27)
					(thickness 0.15)
				)
				(justify left bottom)
				(hide yes)
			)
		)
		(property "Description" "SMD Chip Resistor, Jumper, 0 ohm, 100 mW, 0402 [1005 Metric], Thick Film, General Purpose"
			(at 207.01 41.91 0)
			(effects
				(font
					(size 1.27 1.27)
				)
				(justify left bottom)
				(hide yes)
			)
		)
		(property "MPN" "ERJ2GE0R00X"
			(at 219.71 41.91 0)
			(effects
				(font
					(size 1.27 1.27)
					(thickness 0.15)
				)
				(justify left bottom)
				(hide yes)
			)
		)
		(property "Manufacturer" "Panasonic"
			(at 217.17 41.91 0)
			(effects
				(font
					(size 1.27 1.27)
					(thickness 0.15)
				)
				(justify left bottom)
				(hide yes)
			)
		)
		(property "License" "Apache-2.0"
			(at 214.63 41.91 0)
			(effects
				(font
					(size 1.27 1.27)
					(thickness 0.15)
				)
				(justify left bottom)
				(hide yes)
			)
		)
		(property "Author" "Antmicro"
			(at 212.09 41.91 0)
			(effects
				(font
					(size 1.27 1.27)
					(thickness 0.15)
				)
				(justify left bottom)
				(hide yes)
			)
		)
		(property "Val" "0R"
			(at 242.57 60.96 90)
			(effects
				(font
					(size 1.27 1.27)
					(thickness 0.15)
				)
				(justify left)
			)
		)
		(property "Tolerance" "~"
			(at 229.87 41.91 0)
			(effects
				(font
					(size 1.27 1.27)
				)
				(justify left bottom)
				(hide yes)
			)
		)
		(property "Current" "1A"
			(at 209.55 41.91 0)
			(effects
				(font
					(size 1.27 1.27)
					(thickness 0.15)
				)
				(justify left bottom)
				(hide yes)
			)
		)
		(pin "2"
		)
		(pin "1"
		)
		(instances
			(project ""
				(path ""
					(reference "R3")
					(unit 1)
				)
			)
		)
	)
	(symbol
		(lib_name "+5V_1")
		(lib_id "antmicropower:+5V")
		(at 240.03 52.07 0)
		(unit 1)
		(exclude_from_sim no)
		(in_bom yes)
		(on_board yes)
		(dnp no)
		(fields_autoplaced yes)
		(property "Reference" "#PWR033"
			(at 255.27 54.61 0)
			(effects
				(font
					(size 1.27 1.27)
					(thickness 0.15)
				)
				(justify left bottom)
				(hide yes)
			)
		)
		(property "Value" "+5V"
			(at 240.03 46.99 0)
			(effects
				(font
					(size 1.27 1.27)
					(thickness 0.15)
				)
			)
		)
		(property "Footprint" ""
			(at 255.27 59.69 0)
			(effects
				(font
					(size 1.27 1.27)
					(thickness 0.15)
				)
				(justify left bottom)
				(hide yes)
			)
		)
		(property "Datasheet" ""
			(at 255.27 62.23 0)
			(effects
				(font
					(size 1.27 1.27)
					(thickness 0.15)
				)
				(justify left bottom)
				(hide yes)
			)
		)
		(property "Description" ""
			(at 255.27 64.77 0)
			(effects
				(font
					(size 1.27 1.27)
				)
				(justify left bottom)
				(hide yes)
			)
		)
		(property "Author" "Antmicro"
			(at 255.27 59.69 0)
			(effects
				(font
					(size 1.27 1.27)
					(thickness 0.15)
				)
				(justify left bottom)
				(hide yes)
			)
		)
		(property "License" "Apache-2.0"
			(at 255.27 62.23 0)
			(effects
				(font
					(size 1.27 1.27)
					(thickness 0.15)
				)
				(justify left bottom)
				(hide yes)
			)
		)
		(pin "1"
		)
		(instances
			(project ""
				(path ""
					(reference "#PWR033")
					(unit 1)
				)
			)
		)
	)
	(symbol
		(lib_name "R_0R_0402_1")
		(lib_id "antmicroResistors0402:R_0R_0402")
		(at 248.92 62.23 270)
		(mirror x)
		(unit 1)
		(exclude_from_sim no)
		(in_bom no)
		(on_board yes)
		(dnp yes)
		(fields_autoplaced yes)
		(property "Reference" "R4"
			(at 251.46 58.42 90)
			(effects
				(font
					(size 1.27 1.27)
					(thickness 0.15)
				)
				(justify left)
			)
		)
		(property "Value" "R_0R_0402"
			(at 236.22 41.91 0)
			(effects
				(font
					(size 1.27 1.27)
					(thickness 0.15)
				)
				(justify left bottom)
				(hide yes)
			)
		)
		(property "Footprint" "antmicro-footprints:R_0402_1005Metric"
			(at 233.68 41.91 0)
			(effects
				(font
					(size 1.27 1.27)
					(thickness 0.15)
				)
				(justify left bottom)
				(hide yes)
			)
		)
		(property "Datasheet" "https://industrial.panasonic.com/cdbs/www-data/pdf/RDA0000/AOA0000C301.pdf"
			(at 231.14 41.91 0)
			(effects
				(font
					(size 1.27 1.27)
					(thickness 0.15)
				)
				(justify left bottom)
				(hide yes)
			)
		)
		(property "Description" "SMD Chip Resistor, Jumper, 0 ohm, 100 mW, 0402 [1005 Metric], Thick Film, General Purpose"
			(at 215.9 41.91 0)
			(effects
				(font
					(size 1.27 1.27)
				)
				(justify left bottom)
				(hide yes)
			)
		)
		(property "MPN" "ERJ2GE0R00X"
			(at 228.6 41.91 0)
			(effects
				(font
					(size 1.27 1.27)
					(thickness 0.15)
				)
				(justify left bottom)
				(hide yes)
			)
		)
		(property "Manufacturer" "Panasonic"
			(at 226.06 41.91 0)
			(effects
				(font
					(size 1.27 1.27)
					(thickness 0.15)
				)
				(justify left bottom)
				(hide yes)
			)
		)
		(property "License" "Apache-2.0"
			(at 223.52 41.91 0)
			(effects
				(font
					(size 1.27 1.27)
					(thickness 0.15)
				)
				(justify left bottom)
				(hide yes)
			)
		)
		(property "Author" "Antmicro"
			(at 220.98 41.91 0)
			(effects
				(font
					(size 1.27 1.27)
					(thickness 0.15)
				)
				(justify left bottom)
				(hide yes)
			)
		)
		(property "Val" "0R"
			(at 251.46 60.96 90)
			(effects
				(font
					(size 1.27 1.27)
					(thickness 0.15)
				)
				(justify left)
			)
		)
		(property "Tolerance" "~"
			(at 238.76 41.91 0)
			(effects
				(font
					(size 1.27 1.27)
				)
				(justify left bottom)
				(hide yes)
			)
		)
		(property "Current" "1A"
			(at 218.44 41.91 0)
			(effects
				(font
					(size 1.27 1.27)
					(thickness 0.15)
				)
				(justify left bottom)
				(hide yes)
			)
		)
		(pin "2"
		)
		(pin "1"
		)
		(instances
			(project "cm4-baseboard"
				(path ""
					(reference "R4")
					(unit 1)
				)
			)
		)
	)
	(symbol
		(lib_id "antmicropower:GND")
		(at 181.61 198.12 0)
		(unit 1)
		(exclude_from_sim no)
		(in_bom yes)
		(on_board yes)
		(dnp no)
		(fields_autoplaced yes)
		(property "Reference" "#PWR0820"
			(at 190.5 200.66 0)
			(effects
				(font
					(size 1.27 1.27)
					(thickness 0.15)
				)
				(justify left bottom)
				(hide yes)
			)
		)
		(property "Value" "GND"
			(at 181.61 203.2 0)
			(effects
				(font
					(size 1.27 1.27)
				)
			)
		)
		(property "Footprint" ""
			(at 190.5 205.74 0)
			(effects
				(font
					(size 1.27 1.27)
					(thickness 0.15)
				)
				(justify left bottom)
				(hide yes)
			)
		)
		(property "Datasheet" ""
			(at 190.5 210.82 0)
			(effects
				(font
					(size 1.27 1.27)
					(thickness 0.15)
				)
				(justify left bottom)
				(hide yes)
			)
		)
		(property "Description" ""
			(at 181.61 198.12 0)
			(effects
				(font
					(size 1.27 1.27)
				)
				(hide yes)
			)
		)
		(property "Author" "Antmicro"
			(at 190.5 205.74 0)
			(effects
				(font
					(size 1.27 1.27)
					(thickness 0.15)
				)
				(justify left bottom)
				(hide yes)
			)
		)
		(property "License" "Apache-2.0"
			(at 190.5 208.28 0)
			(effects
				(font
					(size 1.27 1.27)
					(thickness 0.15)
				)
				(justify left bottom)
				(hide yes)
			)
		)
		(pin "1"
		)
		(instances
			(project "cm4-baseboard"
				(path ""
					(reference "#PWR0820")
					(unit 1)
				)
			)
		)
	)
	(symbol
		(lib_id "antmicropower:+3V3")
		(at 97.79 39.37 0)
		(unit 1)
		(exclude_from_sim no)
		(in_bom yes)
		(on_board yes)
		(dnp no)
		(property "Reference" "#PWR0807"
			(at 113.03 41.91 0)
			(effects
				(font
					(size 1.27 1.27)
					(thickness 0.15)
				)
				(justify left bottom)
				(hide yes)
			)
		)
		(property "Value" "+3V3"
			(at 97.79 34.29 0)
			(effects
				(font
					(size 1.27 1.27)
					(thickness 0.15)
				)
			)
		)
		(property "Footprint" ""
			(at 113.03 46.99 0)
			(effects
				(font
					(size 1.27 1.27)
					(thickness 0.15)
				)
				(justify left bottom)
				(hide yes)
			)
		)
		(property "Datasheet" ""
			(at 113.03 49.53 0)
			(effects
				(font
					(size 1.27 1.27)
					(thickness 0.15)
				)
				(justify left bottom)
				(hide yes)
			)
		)
		(property "Description" ""
			(at 97.79 39.37 0)
			(effects
				(font
					(size 1.27 1.27)
				)
				(hide yes)
			)
		)
		(property "Author" "Antmicro"
			(at 113.03 46.99 0)
			(effects
				(font
					(size 1.27 1.27)
					(thickness 0.15)
				)
				(justify left bottom)
				(hide yes)
			)
		)
		(property "License" "Apache-2.0"
			(at 113.03 49.53 0)
			(effects
				(font
					(size 1.27 1.27)
					(thickness 0.15)
				)
				(justify left bottom)
				(hide yes)
			)
		)
		(pin "1"
		)
		(instances
			(project "cm4-baseboard"
				(path ""
					(reference "#PWR0807")
					(unit 1)
				)
			)
		)
	)
	(symbol
		(lib_id "antmicropower:GND")
		(at 248.92 88.9 0)
		(unit 1)
		(exclude_from_sim no)
		(in_bom yes)
		(on_board yes)
		(dnp no)
		(property "Reference" "#PWR0828"
			(at 257.81 91.44 0)
			(effects
				(font
					(size 1.27 1.27)
					(thickness 0.15)
				)
				(justify left bottom)
				(hide yes)
			)
		)
		(property "Value" "GND"
			(at 248.92 92.71 0)
			(effects
				(font
					(size 1.27 1.27)
					(thickness 0.15)
				)
			)
		)
		(property "Footprint" ""
			(at 257.81 96.52 0)
			(effects
				(font
					(size 1.27 1.27)
					(thickness 0.15)
				)
				(justify left bottom)
				(hide yes)
			)
		)
		(property "Datasheet" ""
			(at 257.81 101.6 0)
			(effects
				(font
					(size 1.27 1.27)
					(thickness 0.15)
				)
				(justify left bottom)
				(hide yes)
			)
		)
		(property "Description" ""
			(at 248.92 88.9 0)
			(effects
				(font
					(size 1.27 1.27)
				)
				(hide yes)
			)
		)
		(property "Author" "Antmicro"
			(at 257.81 96.52 0)
			(effects
				(font
					(size 1.27 1.27)
					(thickness 0.15)
				)
				(justify left bottom)
				(hide yes)
			)
		)
		(property "License" "Apache-2.0"
			(at 257.81 99.06 0)
			(effects
				(font
					(size 1.27 1.27)
					(thickness 0.15)
				)
				(justify left bottom)
				(hide yes)
			)
		)
		(pin "1"
		)
		(instances
			(project "cm4-baseboard"
				(path ""
					(reference "#PWR0828")
					(unit 1)
				)
			)
		)
	)
	(symbol
		(lib_id "antmicroCapacitors0402:C_100n_0402")
		(at 257.81 82.55 270)
		(unit 1)
		(exclude_from_sim no)
		(in_bom yes)
		(on_board yes)
		(dnp no)
		(fields_autoplaced yes)
		(property "Reference" "C804"
			(at 259.08 83.82 90)
			(effects
				(font
					(size 1.27 1.27)
					(thickness 0.15)
				)
				(justify left)
			)
		)
		(property "Value" "C_100n_0402"
			(at 247.65 102.87 0)
			(effects
				(font
					(size 1.27 1.27)
					(thickness 0.15)
				)
				(justify left bottom)
				(hide yes)
			)
		)
		(property "Footprint" "antmicro-footprints:C_0402_1005Metric"
			(at 245.11 102.87 0)
			(effects
				(font
					(size 1.27 1.27)
					(thickness 0.15)
				)
				(justify left bottom)
				(hide yes)
			)
		)
		(property "Datasheet" "https://www.murata.com/products/productdetail?partno=GRM155R61H104KE14%23"
			(at 242.57 102.87 0)
			(effects
				(font
					(size 1.27 1.27)
					(thickness 0.15)
				)
				(justify left bottom)
				(hide yes)
			)
		)
		(property "Description" ""
			(at 257.81 82.55 0)
			(effects
				(font
					(size 1.27 1.27)
				)
				(hide yes)
			)
		)
		(property "MPN" "GRM155R61H104KE14D"
			(at 240.03 102.87 0)
			(effects
				(font
					(size 1.27 1.27)
					(thickness 0.15)
				)
				(justify left bottom)
				(hide yes)
			)
		)
		(property "Manufacturer" "Murata"
			(at 237.49 102.87 0)
			(effects
				(font
					(size 1.27 1.27)
					(thickness 0.15)
				)
				(justify left bottom)
				(hide yes)
			)
		)
		(property "License" "Apache-2.0"
			(at 234.95 102.87 0)
			(effects
				(font
					(size 1.27 1.27)
					(thickness 0.15)
				)
				(justify left bottom)
				(hide yes)
			)
		)
		(property "Author" "Antmicro"
			(at 232.41 102.87 0)
			(effects
				(font
					(size 1.27 1.27)
					(thickness 0.15)
				)
				(justify left bottom)
				(hide yes)
			)
		)
		(property "Val" "100n"
			(at 259.08 86.36 90)
			(effects
				(font
					(size 1.27 1.27)
					(thickness 0.15)
				)
				(justify left)
			)
		)
		(property "Voltage" "50V"
			(at 229.87 102.87 0)
			(effects
				(font
					(size 1.27 1.27)
				)
				(justify left bottom)
				(hide yes)
			)
		)
		(property "Dielectric" "X5R"
			(at 227.33 102.87 0)
			(effects
				(font
					(size 1.27 1.27)
				)
				(justify left bottom)
				(hide yes)
			)
		)
		(pin "1"
		)
		(pin "2"
		)
		(instances
			(project "cm4-baseboard"
				(path ""
					(reference "C804")
					(unit 1)
				)
			)
		)
	)
	(symbol
		(lib_id "antmicroCapacitors0402:C_470p_100V_0402")
		(at 331.47 114.3 90)
		(unit 1)
		(exclude_from_sim no)
		(in_bom yes)
		(on_board yes)
		(dnp no)
		(property "Reference" "C818"
			(at 332.994 110.49 90)
			(effects
				(font
					(size 1.27 1.27)
					(thickness 0.15)
				)
				(justify right)
			)
		)
		(property "Value" "C_470p_100V_0402"
			(at 341.63 93.98 0)
			(effects
				(font
					(size 1.27 1.27)
					(thickness 0.15)
				)
				(justify left bottom)
				(hide yes)
			)
		)
		(property "Footprint" "antmicro-footprints:C_0402_1005Metric"
			(at 344.17 93.98 0)
			(effects
				(font
					(size 1.27 1.27)
					(thickness 0.15)
				)
				(justify left bottom)
				(hide yes)
			)
		)
		(property "Datasheet" "https://search.murata.co.jp/Ceramy/image/img/A01X/G101/ENG/GRM1555C2A471JE01-01A.pdf"
			(at 346.71 93.98 0)
			(effects
				(font
					(size 1.27 1.27)
					(thickness 0.15)
				)
				(justify left bottom)
				(hide yes)
			)
		)
		(property "Description" "MLCC, SMD/SMT, 100V, 470pF, C0G/NP0, 0402 5%"
			(at 364.49 93.98 0)
			(effects
				(font
					(size 1.27 1.27)
				)
				(justify left bottom)
				(hide yes)
			)
		)
		(property "MPN" "GRM1555C2A471JE01D"
			(at 349.25 93.98 0)
			(effects
				(font
					(size 1.27 1.27)
					(thickness 0.15)
				)
				(justify left bottom)
				(hide yes)
			)
		)
		(property "Manufacturer" "Murata"
			(at 351.79 93.98 0)
			(effects
				(font
					(size 1.27 1.27)
					(thickness 0.15)
				)
				(justify left bottom)
				(hide yes)
			)
		)
		(property "License" "Apache-2.0"
			(at 354.33 93.98 0)
			(effects
				(font
					(size 1.27 1.27)
					(thickness 0.15)
				)
				(justify left bottom)
				(hide yes)
			)
		)
		(property "Author" "Antmicro"
			(at 356.87 93.98 0)
			(effects
				(font
					(size 1.27 1.27)
					(thickness 0.15)
				)
				(justify left bottom)
				(hide yes)
			)
		)
		(property "Val" "470p"
			(at 332.994 113.03 90)
			(effects
				(font
					(size 1.27 1.27)
					(thickness 0.15)
				)
				(justify right)
			)
		)
		(property "Voltage" "100V"
			(at 359.41 93.98 0)
			(effects
				(font
					(size 1.27 1.27)
				)
				(justify left bottom)
				(hide yes)
			)
		)
		(property "Dielectric" "C0G/NP0"
			(at 361.95 93.98 0)
			(effects
				(font
					(size 1.27 1.27)
				)
				(justify left bottom)
				(hide yes)
			)
		)
		(pin "1"
		)
		(pin "2"
		)
		(instances
			(project "cm4-baseboard"
				(path ""
					(reference "C818")
					(unit 1)
				)
			)
		)
	)
	(symbol
		(lib_id "antmicroClockTimingRealTimeClocks:DS1338_SOIC")
		(at 257.81 220.98 0)
		(unit 1)
		(exclude_from_sim no)
		(in_bom yes)
		(on_board yes)
		(dnp no)
		(fields_autoplaced yes)
		(property "Reference" "U802"
			(at 267.97 213.36 0)
			(effects
				(font
					(size 1.27 1.27)
					(thickness 0.15)
				)
			)
		)
		(property "Value" "DS1338_SOIC"
			(at 290.83 233.68 0)
			(effects
				(font
					(size 1.27 1.27)
					(thickness 0.15)
				)
				(justify left bottom)
				(hide yes)
			)
		)
		(property "Footprint" "antmicro-footprints:SOIC-8_3.9x4.9x1.75mm_P1.27mm"
			(at 290.83 236.22 0)
			(effects
				(font
					(size 1.27 1.27)
					(thickness 0.15)
				)
				(justify left bottom)
				(hide yes)
			)
		)
		(property "Datasheet" "https://www.analog.com/media/en/technical-documentation/data-sheets/DS1338-DS1338Z.pdf"
			(at 290.83 238.76 0)
			(effects
				(font
					(size 1.27 1.27)
					(thickness 0.15)
				)
				(justify left bottom)
				(hide yes)
			)
		)
		(property "Description" "Real-time clock/calendar,  1.71V-5.5V supply, I2C, SOIC-8"
			(at 290.83 246.38 0)
			(effects
				(font
					(size 1.27 1.27)
				)
				(justify left bottom)
				(hide yes)
			)
		)
		(property "MPN" "DS1338Z-18+"
			(at 267.97 215.9 0)
			(effects
				(font
					(size 1.27 1.27)
					(thickness 0.15)
				)
			)
		)
		(property "Manufacturer" "Maxim Integrated Products"
			(at 290.83 231.14 0)
			(effects
				(font
					(size 1.27 1.27)
					(thickness 0.15)
				)
				(justify left bottom)
				(hide yes)
			)
		)
		(property "Author" "Antmicro"
			(at 290.83 241.3 0)
			(effects
				(font
					(size 1.27 1.27)
					(thickness 0.15)
				)
				(justify left bottom)
				(hide yes)
			)
		)
		(property "License" "Apache-2.0"
			(at 290.83 243.84 0)
			(effects
				(font
					(size 1.27 1.27)
					(thickness 0.15)
				)
				(justify left bottom)
				(hide yes)
			)
		)
		(pin "5"
		)
		(pin "6"
		)
		(pin "4"
		)
		(pin "3"
		)
		(pin "7"
		)
		(pin "1"
		)
		(pin "8"
		)
		(pin "2"
		)
		(instances
			(project "cm4-baseboard"
				(path ""
					(reference "U802")
					(unit 1)
				)
			)
		)
	)
	(symbol
		(lib_name "R_0R_0402_2")
		(lib_id "antmicroResistors0402:R_0R_0402")
		(at 364.49 123.19 0)
		(mirror x)
		(unit 1)
		(exclude_from_sim no)
		(in_bom yes)
		(on_board yes)
		(dnp no)
		(property "Reference" "R810"
			(at 367.03 125.73 0)
			(effects
				(font
					(size 1.27 1.27)
					(thickness 0.15)
				)
			)
		)
		(property "Value" "R_0R_0402"
			(at 384.81 110.49 0)
			(effects
				(font
					(size 1.27 1.27)
					(thickness 0.15)
				)
				(justify left bottom)
				(hide yes)
			)
		)
		(property "Footprint" "antmicro-footprints:R_0402_1005Metric"
			(at 384.81 107.95 0)
			(effects
				(font
					(size 1.27 1.27)
					(thickness 0.15)
				)
				(justify left bottom)
				(hide yes)
			)
		)
		(property "Datasheet" "https://industrial.panasonic.com/cdbs/www-data/pdf/RDA0000/AOA0000C301.pdf"
			(at 384.81 105.41 0)
			(effects
				(font
					(size 1.27 1.27)
					(thickness 0.15)
				)
				(justify left bottom)
				(hide yes)
			)
		)
		(property "Description" "SMD Chip Resistor, Jumper, 0 ohm, 100 mW, 0402 [1005 Metric], Thick Film, General Purpose"
			(at 384.81 90.17 0)
			(effects
				(font
					(size 1.27 1.27)
				)
				(justify left bottom)
				(hide yes)
			)
		)
		(property "MPN" "ERJ2GE0R00X"
			(at 384.81 102.87 0)
			(effects
				(font
					(size 1.27 1.27)
					(thickness 0.15)
				)
				(justify left bottom)
				(hide yes)
			)
		)
		(property "Manufacturer" "Panasonic"
			(at 384.81 100.33 0)
			(effects
				(font
					(size 1.27 1.27)
					(thickness 0.15)
				)
				(justify left bottom)
				(hide yes)
			)
		)
		(property "License" "Apache-2.0"
			(at 384.81 97.79 0)
			(effects
				(font
					(size 1.27 1.27)
					(thickness 0.15)
				)
				(justify left bottom)
				(hide yes)
			)
		)
		(property "Author" "Antmicro"
			(at 384.81 95.25 0)
			(effects
				(font
					(size 1.27 1.27)
					(thickness 0.15)
				)
				(justify left bottom)
				(hide yes)
			)
		)
		(property "Val" "0R"
			(at 367.03 128.27 0)
			(effects
				(font
					(size 1.27 1.27)
					(thickness 0.15)
				)
			)
		)
		(property "Tolerance" "~"
			(at 384.81 113.03 0)
			(effects
				(font
					(size 1.27 1.27)
				)
				(justify left bottom)
				(hide yes)
			)
		)
		(property "Current" "1A"
			(at 384.81 92.71 0)
			(effects
				(font
					(size 1.27 1.27)
					(thickness 0.15)
				)
				(justify left bottom)
				(hide yes)
			)
		)
		(pin "2"
		)
		(pin "1"
		)
		(instances
			(project "cm4-baseboard"
				(path ""
					(reference "R810")
					(unit 1)
				)
			)
		)
	)
	(symbol
		(lib_id "antmicroTVSDiodes:PUSB3F96X_PASS")
		(at 182.88 207.01 0)
		(unit 1)
		(exclude_from_sim no)
		(in_bom yes)
		(on_board yes)
		(dnp no)
		(fields_autoplaced yes)
		(property "Reference" "D809"
			(at 196.85 209.5499 0)
			(effects
				(font
					(size 1.27 1.27)
					(thickness 0.15)
				)
				(justify left)
			)
		)
		(property "Value" "PUSB3F96X_PASS"
			(at 208.28 214.63 0)
			(effects
				(font
					(size 1.27 1.27)
					(thickness 0.15)
				)
				(justify left bottom)
				(hide yes)
			)
		)
		(property "Footprint" "antmicro-footprints:Nexperia_DFN-10_2.5x1mm_P0.5mm"
			(at 208.28 217.17 0)
			(effects
				(font
					(size 1.27 1.27)
					(thickness 0.15)
				)
				(justify left bottom)
				(hide yes)
			)
		)
		(property "Datasheet" "https://mouser.com/datasheet/2/916/PUSB3F96-1600324.pdf"
			(at 208.28 219.71 0)
			(effects
				(font
					(size 1.27 1.27)
					(thickness 0.15)
				)
				(justify left bottom)
				(hide yes)
			)
		)
		(property "Description" ""
			(at 182.88 207.01 0)
			(effects
				(font
					(size 1.27 1.27)
				)
				(hide yes)
			)
		)
		(property "Manufacturer" "Nexperia"
			(at 208.28 222.25 0)
			(effects
				(font
					(size 1.27 1.27)
					(thickness 0.15)
				)
				(justify left bottom)
				(hide yes)
			)
		)
		(property "MPN" "PUSB3F96X"
			(at 196.85 212.0899 0)
			(effects
				(font
					(size 1.27 1.27)
					(thickness 0.15)
				)
				(justify left)
			)
		)
		(property "Author" "Antmicro"
			(at 208.28 224.79 0)
			(effects
				(font
					(size 1.27 1.27)
					(thickness 0.15)
				)
				(justify left bottom)
				(hide yes)
			)
		)
		(property "License" "Apache-2.0"
			(at 208.28 227.33 0)
			(effects
				(font
					(size 1.27 1.27)
					(thickness 0.15)
				)
				(justify left bottom)
				(hide yes)
			)
		)
		(pin "1"
		)
		(pin "10"
		)
		(pin "2"
		)
		(pin "3"
		)
		(pin "4"
		)
		(pin "5"
		)
		(pin "6"
		)
		(pin "7"
		)
		(pin "8"
		)
		(pin "9"
		)
		(instances
			(project "cm4-baseboard"
				(path ""
					(reference "D809")
					(unit 1)
				)
			)
		)
	)
	(symbol
		(lib_id "antmicropower:GND")
		(at 106.68 115.57 0)
		(unit 1)
		(exclude_from_sim no)
		(in_bom yes)
		(on_board yes)
		(dnp no)
		(property "Reference" "#PWR0809"
			(at 115.57 118.11 0)
			(effects
				(font
					(size 1.27 1.27)
					(thickness 0.15)
				)
				(justify left bottom)
				(hide yes)
			)
		)
		(property "Value" "GND"
			(at 106.68 120.65 0)
			(effects
				(font
					(size 1.27 1.27)
					(thickness 0.15)
				)
			)
		)
		(property "Footprint" ""
			(at 115.57 123.19 0)
			(effects
				(font
					(size 1.27 1.27)
					(thickness 0.15)
				)
				(justify left bottom)
				(hide yes)
			)
		)
		(property "Datasheet" ""
			(at 115.57 128.27 0)
			(effects
				(font
					(size 1.27 1.27)
					(thickness 0.15)
				)
				(justify left bottom)
				(hide yes)
			)
		)
		(property "Description" ""
			(at 106.68 115.57 0)
			(effects
				(font
					(size 1.27 1.27)
				)
				(hide yes)
			)
		)
		(property "Author" "Antmicro"
			(at 115.57 123.19 0)
			(effects
				(font
					(size 1.27 1.27)
					(thickness 0.15)
				)
				(justify left bottom)
				(hide yes)
			)
		)
		(property "License" "Apache-2.0"
			(at 115.57 125.73 0)
			(effects
				(font
					(size 1.27 1.27)
					(thickness 0.15)
				)
				(justify left bottom)
				(hide yes)
			)
		)
		(pin "1"
		)
		(instances
			(project "cm4-baseboard"
				(path ""
					(reference "#PWR0809")
					(unit 1)
				)
			)
		)
	)
	(symbol
		(lib_id "antmicropower:GND")
		(at 130.81 217.17 0)
		(unit 1)
		(exclude_from_sim no)
		(in_bom yes)
		(on_board yes)
		(dnp no)
		(fields_autoplaced yes)
		(property "Reference" "#PWR0813"
			(at 139.7 219.71 0)
			(effects
				(font
					(size 1.27 1.27)
					(thickness 0.15)
				)
				(justify left bottom)
				(hide yes)
			)
		)
		(property "Value" "GND"
			(at 130.81 222.25 0)
			(effects
				(font
					(size 1.27 1.27)
				)
			)
		)
		(property "Footprint" ""
			(at 139.7 224.79 0)
			(effects
				(font
					(size 1.27 1.27)
					(thickness 0.15)
				)
				(justify left bottom)
				(hide yes)
			)
		)
		(property "Datasheet" ""
			(at 139.7 229.87 0)
			(effects
				(font
					(size 1.27 1.27)
					(thickness 0.15)
				)
				(justify left bottom)
				(hide yes)
			)
		)
		(property "Description" ""
			(at 130.81 217.17 0)
			(effects
				(font
					(size 1.27 1.27)
				)
				(hide yes)
			)
		)
		(property "Author" "Antmicro"
			(at 139.7 224.79 0)
			(effects
				(font
					(size 1.27 1.27)
					(thickness 0.15)
				)
				(justify left bottom)
				(hide yes)
			)
		)
		(property "License" "Apache-2.0"
			(at 139.7 227.33 0)
			(effects
				(font
					(size 1.27 1.27)
					(thickness 0.15)
				)
				(justify left bottom)
				(hide yes)
			)
		)
		(pin "1"
		)
		(instances
			(project "cm4-baseboard"
				(path ""
					(reference "#PWR0813")
					(unit 1)
				)
			)
		)
	)
	(symbol
		(lib_id "antmicroResistors0402:R_0R_0402")
		(at 96.52 96.52 90)
		(unit 1)
		(exclude_from_sim no)
		(in_bom yes)
		(on_board yes)
		(dnp no)
		(property "Reference" "R802"
			(at 97.79 92.71 90)
			(effects
				(font
					(size 1.27 1.27)
					(thickness 0.15)
				)
				(justify right)
			)
		)
		(property "Value" "R_0R_0402"
			(at 109.22 76.2 0)
			(effects
				(font
					(size 1.27 1.27)
					(thickness 0.15)
				)
				(justify left bottom)
				(hide yes)
			)
		)
		(property "Footprint" "antmicro-footprints:R_0402_1005Metric"
			(at 111.76 76.2 0)
			(effects
				(font
					(size 1.27 1.27)
					(thickness 0.15)
				)
				(justify left bottom)
				(hide yes)
			)
		)
		(property "Datasheet" "https://industrial.panasonic.com/cdbs/www-data/pdf/RDA0000/AOA0000C301.pdf"
			(at 114.3 76.2 0)
			(effects
				(font
					(size 1.27 1.27)
					(thickness 0.15)
				)
				(justify left bottom)
				(hide yes)
			)
		)
		(property "Description" ""
			(at 96.52 96.52 0)
			(effects
				(font
					(size 1.27 1.27)
				)
				(hide yes)
			)
		)
		(property "MPN" "ERJ2GE0R00X"
			(at 116.84 76.2 0)
			(effects
				(font
					(size 1.27 1.27)
					(thickness 0.15)
				)
				(justify left bottom)
				(hide yes)
			)
		)
		(property "Manufacturer" "Panasonic"
			(at 119.38 76.2 0)
			(effects
				(font
					(size 1.27 1.27)
					(thickness 0.15)
				)
				(justify left bottom)
				(hide yes)
			)
		)
		(property "License" "Apache-2.0"
			(at 121.92 76.2 0)
			(effects
				(font
					(size 1.27 1.27)
					(thickness 0.15)
				)
				(justify left bottom)
				(hide yes)
			)
		)
		(property "Author" "Antmicro"
			(at 124.46 76.2 0)
			(effects
				(font
					(size 1.27 1.27)
					(thickness 0.15)
				)
				(justify left bottom)
				(hide yes)
			)
		)
		(property "Val" "0R"
			(at 97.79 95.25 90)
			(effects
				(font
					(size 1.27 1.27)
					(thickness 0.15)
				)
				(justify right)
			)
		)
		(property "Tolerance" "~"
			(at 106.68 76.2 0)
			(effects
				(font
					(size 1.27 1.27)
				)
				(justify left bottom)
				(hide yes)
			)
		)
		(property "Current" "1A"
			(at 127 76.2 0)
			(effects
				(font
					(size 1.27 1.27)
					(thickness 0.15)
				)
				(justify left bottom)
				(hide yes)
			)
		)
		(pin "1"
		)
		(pin "2"
		)
		(instances
			(project "cm4-baseboard"
				(path ""
					(reference "R802")
					(unit 1)
				)
			)
		)
	)
	(symbol
		(lib_id "antmicroCapacitors0402:C_39p_0402")
		(at 350.52 121.92 90)
		(unit 1)
		(exclude_from_sim no)
		(in_bom yes)
		(on_board yes)
		(dnp no)
		(property "Reference" "C825"
			(at 352.298 118.11 90)
			(effects
				(font
					(size 1.27 1.27)
					(thickness 0.15)
				)
				(justify right)
			)
		)
		(property "Value" "C_39p_0402"
			(at 360.68 101.6 0)
			(effects
				(font
					(size 1.27 1.27)
					(thickness 0.15)
				)
				(justify left bottom)
				(hide yes)
			)
		)
		(property "Footprint" "antmicro-footprints:C_0402_1005Metric"
			(at 363.22 101.6 0)
			(effects
				(font
					(size 1.27 1.27)
					(thickness 0.15)
				)
				(justify left bottom)
				(hide yes)
			)
		)
		(property "Datasheet" "https://spicat.kyocera-avx.com/product/mlcc/chartview/04025A390JAT2A/"
			(at 365.76 101.6 0)
			(effects
				(font
					(size 1.27 1.27)
					(thickness 0.15)
				)
				(justify left bottom)
				(hide yes)
			)
		)
		(property "Description" "SMD Multilayer Ceramic Capacitor, 39 pF, 50 V, 0402 [1005 Metric], ± 5%, C0G / NP0, AVX 0402 MLCC"
			(at 383.54 101.6 0)
			(effects
				(font
					(size 1.27 1.27)
				)
				(justify left bottom)
				(hide yes)
			)
		)
		(property "MPN" "04025A390JAT2A"
			(at 368.3 101.6 0)
			(effects
				(font
					(size 1.27 1.27)
					(thickness 0.15)
				)
				(justify left bottom)
				(hide yes)
			)
		)
		(property "Manufacturer" "KYOCERA AVX"
			(at 370.84 101.6 0)
			(effects
				(font
					(size 1.27 1.27)
					(thickness 0.15)
				)
				(justify left bottom)
				(hide yes)
			)
		)
		(property "License" "Apache-2.0"
			(at 373.38 101.6 0)
			(effects
				(font
					(size 1.27 1.27)
					(thickness 0.15)
				)
				(justify left bottom)
				(hide yes)
			)
		)
		(property "Author" "Antmicro"
			(at 375.92 101.6 0)
			(effects
				(font
					(size 1.27 1.27)
					(thickness 0.15)
				)
				(justify left bottom)
				(hide yes)
			)
		)
		(property "Val" "39p"
			(at 352.298 120.65 90)
			(effects
				(font
					(size 1.27 1.27)
					(thickness 0.15)
				)
				(justify right)
			)
		)
		(property "Voltage" ""
			(at 378.46 101.6 0)
			(effects
				(font
					(size 1.27 1.27)
				)
				(justify left bottom)
				(hide yes)
			)
		)
		(property "Dielectric" ""
			(at 381 101.6 0)
			(effects
				(font
					(size 1.27 1.27)
				)
				(justify left bottom)
				(hide yes)
			)
		)
		(pin "2"
		)
		(pin "1"
		)
		(instances
			(project "cm4-baseboard"
				(path ""
					(reference "C825")
					(unit 1)
				)
			)
		)
	)
	(symbol
		(lib_id "antmicropower:+3V3")
		(at 130.81 163.83 0)
		(unit 1)
		(exclude_from_sim no)
		(in_bom yes)
		(on_board yes)
		(dnp no)
		(fields_autoplaced yes)
		(property "Reference" "#PWR0810"
			(at 146.05 163.83 0)
			(effects
				(font
					(size 1.27 1.27)
					(thickness 0.15)
				)
				(justify left bottom)
				(hide yes)
			)
		)
		(property "Value" "+3V3"
			(at 130.81 158.75 0)
			(effects
				(font
					(size 1.27 1.27)
					(thickness 0.15)
				)
			)
		)
		(property "Footprint" ""
			(at 146.05 171.45 0)
			(effects
				(font
					(size 1.27 1.27)
					(thickness 0.15)
				)
				(justify left bottom)
				(hide yes)
			)
		)
		(property "Datasheet" ""
			(at 146.05 173.99 0)
			(effects
				(font
					(size 1.27 1.27)
					(thickness 0.15)
				)
				(justify left bottom)
				(hide yes)
			)
		)
		(property "Description" ""
			(at 130.81 163.83 0)
			(effects
				(font
					(size 1.27 1.27)
				)
				(hide yes)
			)
		)
		(property "Author" "Antmicro"
			(at 146.05 166.37 0)
			(effects
				(font
					(size 1.27 1.27)
					(thickness 0.15)
				)
				(justify left bottom)
				(hide yes)
			)
		)
		(property "License" "Apache-2.0"
			(at 146.05 168.91 0)
			(effects
				(font
					(size 1.27 1.27)
					(thickness 0.15)
				)
				(justify left bottom)
				(hide yes)
			)
		)
		(pin "1"
		)
		(instances
			(project "cm4-baseboard"
				(path ""
					(reference "#PWR0810")
					(unit 1)
				)
			)
		)
	)
	(symbol
		(lib_id "antmicropower:GND")
		(at 106.68 53.34 0)
		(unit 1)
		(exclude_from_sim no)
		(in_bom yes)
		(on_board yes)
		(dnp no)
		(property "Reference" "#PWR0808"
			(at 115.57 55.88 0)
			(effects
				(font
					(size 1.27 1.27)
					(thickness 0.15)
				)
				(justify left bottom)
				(hide yes)
			)
		)
		(property "Value" "GND"
			(at 106.68 58.42 0)
			(effects
				(font
					(size 1.27 1.27)
					(thickness 0.15)
				)
			)
		)
		(property "Footprint" ""
			(at 115.57 60.96 0)
			(effects
				(font
					(size 1.27 1.27)
					(thickness 0.15)
				)
				(justify left bottom)
				(hide yes)
			)
		)
		(property "Datasheet" ""
			(at 115.57 66.04 0)
			(effects
				(font
					(size 1.27 1.27)
					(thickness 0.15)
				)
				(justify left bottom)
				(hide yes)
			)
		)
		(property "Description" ""
			(at 106.68 53.34 0)
			(effects
				(font
					(size 1.27 1.27)
				)
				(hide yes)
			)
		)
		(property "Author" "Antmicro"
			(at 115.57 60.96 0)
			(effects
				(font
					(size 1.27 1.27)
					(thickness 0.15)
				)
				(justify left bottom)
				(hide yes)
			)
		)
		(property "License" "Apache-2.0"
			(at 115.57 63.5 0)
			(effects
				(font
					(size 1.27 1.27)
					(thickness 0.15)
				)
				(justify left bottom)
				(hide yes)
			)
		)
		(pin "1"
		)
		(instances
			(project "cm4-baseboard"
				(path ""
					(reference "#PWR0808")
					(unit 1)
				)
			)
		)
	)
	(symbol
		(lib_id "antmicropower:GND")
		(at 257.81 88.9 0)
		(unit 1)
		(exclude_from_sim no)
		(in_bom yes)
		(on_board yes)
		(dnp no)
		(property "Reference" "#PWR0831"
			(at 266.7 91.44 0)
			(effects
				(font
					(size 1.27 1.27)
					(thickness 0.15)
				)
				(justify left bottom)
				(hide yes)
			)
		)
		(property "Value" "GND"
			(at 257.81 92.71 0)
			(effects
				(font
					(size 1.27 1.27)
					(thickness 0.15)
				)
			)
		)
		(property "Footprint" ""
			(at 266.7 96.52 0)
			(effects
				(font
					(size 1.27 1.27)
					(thickness 0.15)
				)
				(justify left bottom)
				(hide yes)
			)
		)
		(property "Datasheet" ""
			(at 266.7 101.6 0)
			(effects
				(font
					(size 1.27 1.27)
					(thickness 0.15)
				)
				(justify left bottom)
				(hide yes)
			)
		)
		(property "Description" ""
			(at 257.81 88.9 0)
			(effects
				(font
					(size 1.27 1.27)
				)
				(hide yes)
			)
		)
		(property "Author" "Antmicro"
			(at 266.7 96.52 0)
			(effects
				(font
					(size 1.27 1.27)
					(thickness 0.15)
				)
				(justify left bottom)
				(hide yes)
			)
		)
		(property "License" "Apache-2.0"
			(at 266.7 99.06 0)
			(effects
				(font
					(size 1.27 1.27)
					(thickness 0.15)
				)
				(justify left bottom)
				(hide yes)
			)
		)
		(pin "1"
		)
		(instances
			(project "cm4-baseboard"
				(path ""
					(reference "#PWR0831")
					(unit 1)
				)
			)
		)
	)
	(symbol
		(lib_id "antmicroCapacitors0402:C_12p_0402")
		(at 309.88 138.43 0)
		(mirror x)
		(unit 1)
		(exclude_from_sim no)
		(in_bom yes)
		(on_board yes)
		(dnp no)
		(property "Reference" "C814"
			(at 315.722 137.16 0)
			(effects
				(font
					(size 1.27 1.27)
					(thickness 0.15)
				)
			)
		)
		(property "Value" "C_12p_0402"
			(at 330.2 128.27 0)
			(effects
				(font
					(size 1.27 1.27)
					(thickness 0.15)
				)
				(justify left bottom)
				(hide yes)
			)
		)
		(property "Footprint" "antmicro-footprints:C_0402_1005Metric"
			(at 330.2 125.73 0)
			(effects
				(font
					(size 1.27 1.27)
					(thickness 0.15)
				)
				(justify left bottom)
				(hide yes)
			)
		)
		(property "Datasheet" "https://product.tdk.com/en/search/capacitor/ceramic/mlcc/info?part_no=CGA2B2C0G1H120J050BA"
			(at 330.2 123.19 0)
			(effects
				(font
					(size 1.27 1.27)
					(thickness 0.15)
				)
				(justify left bottom)
				(hide yes)
			)
		)
		(property "Description" "SMD Multilayer Ceramic Capacitor, 12 pF, 50 V, 0402 [1005 Metric], ± 5%, C0G / NP0, CGA"
			(at 330.2 105.41 0)
			(effects
				(font
					(size 1.27 1.27)
				)
				(justify left bottom)
				(hide yes)
			)
		)
		(property "MPN" "CGA2B2C0G1H120J050BA"
			(at 330.2 120.65 0)
			(effects
				(font
					(size 1.27 1.27)
					(thickness 0.15)
				)
				(justify left bottom)
				(hide yes)
			)
		)
		(property "Manufacturer" "TDK"
			(at 330.2 118.11 0)
			(effects
				(font
					(size 1.27 1.27)
					(thickness 0.15)
				)
				(justify left bottom)
				(hide yes)
			)
		)
		(property "License" "Apache-2.0"
			(at 330.2 115.57 0)
			(effects
				(font
					(size 1.27 1.27)
					(thickness 0.15)
				)
				(justify left bottom)
				(hide yes)
			)
		)
		(property "Author" "Antmicro"
			(at 330.2 113.03 0)
			(effects
				(font
					(size 1.27 1.27)
					(thickness 0.15)
				)
				(justify left bottom)
				(hide yes)
			)
		)
		(property "Val" "12p"
			(at 315.976 139.7 0)
			(effects
				(font
					(size 1.27 1.27)
					(thickness 0.15)
				)
			)
		)
		(property "Voltage" ""
			(at 330.2 110.49 0)
			(effects
				(font
					(size 1.27 1.27)
				)
				(justify left bottom)
				(hide yes)
			)
		)
		(property "Dielectric" ""
			(at 330.2 107.95 0)
			(effects
				(font
					(size 1.27 1.27)
				)
				(justify left bottom)
				(hide yes)
			)
		)
		(pin "2"
		)
		(pin "1"
		)
		(instances
			(project ""
				(path ""
					(reference "C814")
					(unit 1)
				)
			)
		)
	)
	(symbol
		(lib_id "antmicropower:GND")
		(at 346.71 116.84 0)
		(unit 1)
		(exclude_from_sim no)
		(in_bom yes)
		(on_board yes)
		(dnp no)
		(property "Reference" "#PWR0836"
			(at 355.6 119.38 0)
			(effects
				(font
					(size 1.27 1.27)
					(thickness 0.15)
				)
				(justify left bottom)
				(hide yes)
			)
		)
		(property "Value" "GND"
			(at 346.71 120.65 0)
			(effects
				(font
					(size 1.27 1.27)
					(thickness 0.15)
				)
			)
		)
		(property "Footprint" ""
			(at 355.6 124.46 0)
			(effects
				(font
					(size 1.27 1.27)
					(thickness 0.15)
				)
				(justify left bottom)
				(hide yes)
			)
		)
		(property "Datasheet" ""
			(at 355.6 129.54 0)
			(effects
				(font
					(size 1.27 1.27)
					(thickness 0.15)
				)
				(justify left bottom)
				(hide yes)
			)
		)
		(property "Description" ""
			(at 346.71 116.84 0)
			(effects
				(font
					(size 1.27 1.27)
				)
				(hide yes)
			)
		)
		(property "Author" "Antmicro"
			(at 355.6 124.46 0)
			(effects
				(font
					(size 1.27 1.27)
					(thickness 0.15)
				)
				(justify left bottom)
				(hide yes)
			)
		)
		(property "License" "Apache-2.0"
			(at 355.6 127 0)
			(effects
				(font
					(size 1.27 1.27)
					(thickness 0.15)
				)
				(justify left bottom)
				(hide yes)
			)
		)
		(pin "1"
		)
		(instances
			(project "cm4-baseboard"
				(path ""
					(reference "#PWR0836")
					(unit 1)
				)
			)
		)
	)
	(symbol
		(lib_id "antmicroBatteryHoldersClipsContacts:Battery_Holder_MS621FE-FL11E")
		(at 300.99 228.6 0)
		(unit 1)
		(exclude_from_sim no)
		(in_bom yes)
		(on_board yes)
		(dnp no)
		(fields_autoplaced yes)
		(property "Reference" "BT801"
			(at 304.8 231.775 0)
			(effects
				(font
					(size 1.27 1.27)
					(thickness 0.15)
				)
				(justify left)
			)
		)
		(property "Value" "Battery_Holder_MS621FE-FL11E"
			(at 318.77 236.22 0)
			(effects
				(font
					(size 1.27 1.27)
					(thickness 0.15)
				)
				(justify left bottom)
				(hide yes)
			)
		)
		(property "Footprint" "antmicro-footprints:MS621FE-FL11E"
			(at 318.77 238.76 0)
			(effects
				(font
					(size 1.27 1.27)
					(thickness 0.15)
				)
				(justify left bottom)
				(hide yes)
			)
		)
		(property "Datasheet" "https://www.sii.co.jp/en/me/datasheets/ms-rechargeable/ms621fe/"
			(at 318.77 241.3 0)
			(effects
				(font
					(size 1.27 1.27)
					(thickness 0.15)
				)
				(justify left bottom)
				(hide yes)
			)
		)
		(property "Description" "Rechargeable Battery, Coin Cell, Single Cell, 3 V, Lithium Manganese Dioxide, 5.5 mAh, Button Cell"
			(at 318.77 251.46 0)
			(effects
				(font
					(size 1.27 1.27)
				)
				(justify left bottom)
				(hide yes)
			)
		)
		(property "Manufacturer" "Seiko Instruments"
			(at 318.77 243.84 0)
			(effects
				(font
					(size 1.27 1.27)
					(thickness 0.15)
				)
				(justify left bottom)
				(hide yes)
			)
		)
		(property "MPN" "MS621FE-FL11E"
			(at 304.8 234.315 0)
			(effects
				(font
					(size 1.27 1.27)
					(thickness 0.15)
				)
				(justify left)
			)
		)
		(property "Author" "Antmicro"
			(at 318.77 246.38 0)
			(effects
				(font
					(size 1.27 1.27)
					(thickness 0.15)
				)
				(justify left bottom)
				(hide yes)
			)
		)
		(property "License" "Apache-2.0"
			(at 318.77 248.92 0)
			(effects
				(font
					(size 1.27 1.27)
					(thickness 0.15)
				)
				(justify left bottom)
				(hide yes)
			)
		)
		(pin "2"
		)
		(pin "1"
		)
		(instances
			(project "cm4-baseboard"
				(path ""
					(reference "BT801")
					(unit 1)
				)
			)
		)
	)
	(symbol
		(lib_id "antmicropower:+3V3")
		(at 248.92 52.07 0)
		(unit 1)
		(exclude_from_sim no)
		(in_bom yes)
		(on_board yes)
		(dnp no)
		(property "Reference" "#PWR0827"
			(at 264.16 54.61 0)
			(effects
				(font
					(size 1.27 1.27)
					(thickness 0.15)
				)
				(justify left bottom)
				(hide yes)
			)
		)
		(property "Value" "+3V3"
			(at 248.92 46.99 0)
			(effects
				(font
					(size 1.27 1.27)
					(thickness 0.15)
				)
			)
		)
		(property "Footprint" ""
			(at 264.16 59.69 0)
			(effects
				(font
					(size 1.27 1.27)
					(thickness 0.15)
				)
				(justify left bottom)
				(hide yes)
			)
		)
		(property "Datasheet" ""
			(at 264.16 62.23 0)
			(effects
				(font
					(size 1.27 1.27)
					(thickness 0.15)
				)
				(justify left bottom)
				(hide yes)
			)
		)
		(property "Description" ""
			(at 248.92 52.07 0)
			(effects
				(font
					(size 1.27 1.27)
				)
				(hide yes)
			)
		)
		(property "Author" "Antmicro"
			(at 264.16 59.69 0)
			(effects
				(font
					(size 1.27 1.27)
					(thickness 0.15)
				)
				(justify left bottom)
				(hide yes)
			)
		)
		(property "License" "Apache-2.0"
			(at 264.16 62.23 0)
			(effects
				(font
					(size 1.27 1.27)
					(thickness 0.15)
				)
				(justify left bottom)
				(hide yes)
			)
		)
		(pin "1"
		)
		(instances
			(project "cm4-baseboard"
				(path ""
					(reference "#PWR0827")
					(unit 1)
				)
			)
		)
	)
	(symbol
		(lib_id "antmicropower:GND")
		(at 181.61 218.44 0)
		(unit 1)
		(exclude_from_sim no)
		(in_bom yes)
		(on_board yes)
		(dnp no)
		(fields_autoplaced yes)
		(property "Reference" "#PWR0821"
			(at 190.5 220.98 0)
			(effects
				(font
					(size 1.27 1.27)
					(thickness 0.15)
				)
				(justify left bottom)
				(hide yes)
			)
		)
		(property "Value" "GND"
			(at 181.61 223.52 0)
			(effects
				(font
					(size 1.27 1.27)
				)
			)
		)
		(property "Footprint" ""
			(at 190.5 226.06 0)
			(effects
				(font
					(size 1.27 1.27)
					(thickness 0.15)
				)
				(justify left bottom)
				(hide yes)
			)
		)
		(property "Datasheet" ""
			(at 190.5 231.14 0)
			(effects
				(font
					(size 1.27 1.27)
					(thickness 0.15)
				)
				(justify left bottom)
				(hide yes)
			)
		)
		(property "Description" ""
			(at 181.61 218.44 0)
			(effects
				(font
					(size 1.27 1.27)
				)
				(hide yes)
			)
		)
		(property "Author" "Antmicro"
			(at 190.5 226.06 0)
			(effects
				(font
					(size 1.27 1.27)
					(thickness 0.15)
				)
				(justify left bottom)
				(hide yes)
			)
		)
		(property "License" "Apache-2.0"
			(at 190.5 228.6 0)
			(effects
				(font
					(size 1.27 1.27)
					(thickness 0.15)
				)
				(justify left bottom)
				(hide yes)
			)
		)
		(pin "1"
		)
		(instances
			(project "cm4-baseboard"
				(path ""
					(reference "#PWR0821")
					(unit 1)
				)
			)
		)
	)
	(symbol
		(lib_id "antmicroCapacitors0402:C_template_name_0402")
		(at 360.68 114.3 90)
		(unit 1)
		(exclude_from_sim no)
		(in_bom no)
		(on_board yes)
		(dnp yes)
		(property "Reference" "C826"
			(at 362.712 111.506 90)
			(effects
				(font
					(size 1.27 1.27)
					(thickness 0.15)
				)
				(justify right)
			)
		)
		(property "Value" "C_template_name_0402"
			(at 370.84 93.98 0)
			(effects
				(font
					(size 1.27 1.27)
					(thickness 0.15)
				)
				(justify left bottom)
				(hide yes)
			)
		)
		(property "Footprint" "antmicro-footprints:C_0402_1005Metric"
			(at 373.38 93.98 0)
			(effects
				(font
					(size 1.27 1.27)
					(thickness 0.15)
				)
				(justify left bottom)
				(hide yes)
			)
		)
		(property "Datasheet" "template_datasheet"
			(at 375.92 93.98 0)
			(effects
				(font
					(size 1.27 1.27)
					(thickness 0.15)
				)
				(justify left bottom)
				(hide yes)
			)
		)
		(property "Description" ""
			(at 360.68 114.3 0)
			(effects
				(font
					(size 1.27 1.27)
				)
				(hide yes)
			)
		)
		(property "MPN" "template_MPN"
			(at 378.46 93.98 0)
			(effects
				(font
					(size 1.27 1.27)
					(thickness 0.15)
				)
				(justify left bottom)
				(hide yes)
			)
		)
		(property "Manufacturer" "template_manufacturer"
			(at 381 93.98 0)
			(effects
				(font
					(size 1.27 1.27)
					(thickness 0.15)
				)
				(justify left bottom)
				(hide yes)
			)
		)
		(property "License" "Apache-2.0"
			(at 383.54 93.98 0)
			(effects
				(font
					(size 1.27 1.27)
					(thickness 0.15)
				)
				(justify left bottom)
				(hide yes)
			)
		)
		(property "Author" "Antmicro"
			(at 386.08 93.98 0)
			(effects
				(font
					(size 1.27 1.27)
					(thickness 0.15)
				)
				(justify left bottom)
				(hide yes)
			)
		)
		(property "Val" "template_value"
			(at 356.87 111.7537 0)
			(effects
				(font
					(size 1.27 1.27)
					(thickness 0.15)
				)
				(hide yes)
			)
		)
		(property "Voltage" "template_voltage"
			(at 388.62 93.98 0)
			(effects
				(font
					(size 1.27 1.27)
				)
				(justify left bottom)
				(hide yes)
			)
		)
		(property "Dielectric" "template_dielectric"
			(at 391.16 93.98 0)
			(effects
				(font
					(size 1.27 1.27)
				)
				(justify left bottom)
				(hide yes)
			)
		)
		(pin "1"
		)
		(pin "2"
		)
		(instances
			(project "cm4-baseboard"
				(path ""
					(reference "C826")
					(unit 1)
				)
			)
		)
	)
	(symbol
		(lib_id "antmicroResistors0402:R_2k2_0402")
		(at 300.99 227.33 90)
		(unit 1)
		(exclude_from_sim no)
		(in_bom yes)
		(on_board yes)
		(dnp no)
		(fields_autoplaced yes)
		(property "Reference" "R811"
			(at 303.53 223.52 90)
			(effects
				(font
					(size 1.27 1.27)
					(thickness 0.15)
				)
				(justify right)
			)
		)
		(property "Value" "R_2k2_0402"
			(at 313.69 207.01 0)
			(effects
				(font
					(size 1.27 1.27)
					(thickness 0.15)
				)
				(justify left bottom)
				(hide yes)
			)
		)
		(property "Footprint" "antmicro-footprints:R_0402_1005Metric"
			(at 316.23 207.01 0)
			(effects
				(font
					(size 1.27 1.27)
					(thickness 0.15)
				)
				(justify left bottom)
				(hide yes)
			)
		)
		(property "Datasheet" "https://www.bourns.com/docs/product-datasheets/cr.pdf"
			(at 318.77 207.01 0)
			(effects
				(font
					(size 1.27 1.27)
					(thickness 0.15)
				)
				(justify left bottom)
				(hide yes)
			)
		)
		(property "Description" "SMD Chip Resistor, 2.2 kohm, ± 1%, 62.5 mW, 0402 [1005 Metric], Thick Film, General Purpose"
			(at 331.47 207.01 0)
			(effects
				(font
					(size 1.27 1.27)
				)
				(justify left bottom)
				(hide yes)
			)
		)
		(property "MPN" "CR0402-FX-2201GLF"
			(at 321.31 207.01 0)
			(effects
				(font
					(size 1.27 1.27)
					(thickness 0.15)
				)
				(justify left bottom)
				(hide yes)
			)
		)
		(property "Manufacturer" "Bourns"
			(at 323.85 207.01 0)
			(effects
				(font
					(size 1.27 1.27)
					(thickness 0.15)
				)
				(justify left bottom)
				(hide yes)
			)
		)
		(property "License" "Apache-2.0"
			(at 326.39 207.01 0)
			(effects
				(font
					(size 1.27 1.27)
					(thickness 0.15)
				)
				(justify left bottom)
				(hide yes)
			)
		)
		(property "Author" "Antmicro"
			(at 328.93 207.01 0)
			(effects
				(font
					(size 1.27 1.27)
					(thickness 0.15)
				)
				(justify left bottom)
				(hide yes)
			)
		)
		(property "Val" "2k2"
			(at 303.53 226.06 90)
			(effects
				(font
					(size 1.27 1.27)
					(thickness 0.15)
				)
				(justify right)
			)
		)
		(property "Tolerance" "1%"
			(at 311.15 207.01 0)
			(effects
				(font
					(size 1.27 1.27)
				)
				(justify left bottom)
				(hide yes)
			)
		)
		(pin "1"
		)
		(pin "2"
		)
		(instances
			(project "cm4-baseboard"
				(path ""
					(reference "R811")
					(unit 1)
				)
			)
		)
	)
	(symbol
		(lib_id "antmicroTestPoints:TP_0.75mm_SMD")
		(at 275.59 109.22 180)
		(unit 1)
		(exclude_from_sim no)
		(in_bom no)
		(on_board yes)
		(dnp no)
		(property "Reference" "TP802"
			(at 271.78 109.22 0)
			(effects
				(font
					(size 1.27 1.27)
					(thickness 0.15)
				)
				(justify left)
			)
		)
		(property "Value" "TP_0.75mm_SMD"
			(at 260.35 101.6 0)
			(effects
				(font
					(size 1.27 1.27)
					(thickness 0.15)
				)
				(justify left bottom)
				(hide yes)
			)
		)
		(property "Footprint" "antmicro-footprints:TP_SMD_0.75mm"
			(at 264.795 102.87 0)
			(effects
				(font
					(size 1.27 1.27)
					(thickness 0.15)
				)
				(justify left bottom)
				(hide yes)
			)
		)
		(property "Datasheet" ""
			(at 257.81 96.52 0)
			(effects
				(font
					(size 1.27 1.27)
					(thickness 0.15)
				)
				(justify left bottom)
				(hide yes)
			)
		)
		(property "Description" ""
			(at 275.59 109.22 0)
			(effects
				(font
					(size 1.27 1.27)
				)
				(hide yes)
			)
		)
		(property "Author" "Antmicro"
			(at 264.795 100.33 0)
			(effects
				(font
					(size 1.27 1.27)
					(thickness 0.15)
				)
				(justify left bottom)
				(hide yes)
			)
		)
		(property "License" "Apache-2.0"
			(at 264.795 97.79 0)
			(effects
				(font
					(size 1.27 1.27)
					(thickness 0.15)
				)
				(justify left bottom)
				(hide yes)
			)
		)
		(property "MPN" ""
			(at 264.795 97.79 0)
			(effects
				(font
					(size 1.27 1.27)
					(thickness 0.15)
				)
				(justify left bottom)
				(hide yes)
			)
		)
		(property "Manufacturer" ""
			(at 264.795 102.87 0)
			(effects
				(font
					(size 1.27 1.27)
					(thickness 0.15)
				)
				(justify left bottom)
				(hide yes)
			)
		)
		(pin "1"
		)
		(instances
			(project "cm4-baseboard"
				(path ""
					(reference "TP802")
					(unit 1)
				)
			)
		)
	)
	(symbol
		(lib_name "C_100n_0402_1")
		(lib_id "antmicroCapacitors0402:C_100n_0402")
		(at 248.92 212.09 270)
		(unit 1)
		(exclude_from_sim no)
		(in_bom yes)
		(on_board yes)
		(dnp no)
		(fields_autoplaced yes)
		(property "Reference" "C828"
			(at 251.46 213.3663 90)
			(effects
				(font
					(size 1.27 1.27)
					(thickness 0.15)
				)
				(justify left)
			)
		)
		(property "Value" "C_100n_0402"
			(at 238.76 232.41 0)
			(effects
				(font
					(size 1.27 1.27)
					(thickness 0.15)
				)
				(justify left bottom)
				(hide yes)
			)
		)
		(property "Footprint" "antmicro-footprints:C_0402_1005Metric"
			(at 236.22 232.41 0)
			(effects
				(font
					(size 1.27 1.27)
					(thickness 0.15)
				)
				(justify left bottom)
				(hide yes)
			)
		)
		(property "Datasheet" "https://www.murata.com/products/productdetail?partno=GRM155R61H104KE14%23"
			(at 233.68 232.41 0)
			(effects
				(font
					(size 1.27 1.27)
					(thickness 0.15)
				)
				(justify left bottom)
				(hide yes)
			)
		)
		(property "Description" "SMD Multilayer Ceramic Capacitor, 0.1 µF, 50 V, 0402 [1005 Metric], ± 10%, X5R, GRM Series"
			(at 215.9 232.41 0)
			(effects
				(font
					(size 1.27 1.27)
				)
				(justify left bottom)
				(hide yes)
			)
		)
		(property "MPN" "GRM155R61H104KE14D"
			(at 231.14 232.41 0)
			(effects
				(font
					(size 1.27 1.27)
					(thickness 0.15)
				)
				(justify left bottom)
				(hide yes)
			)
		)
		(property "Manufacturer" "Murata"
			(at 228.6 232.41 0)
			(effects
				(font
					(size 1.27 1.27)
					(thickness 0.15)
				)
				(justify left bottom)
				(hide yes)
			)
		)
		(property "License" "Apache-2.0"
			(at 226.06 232.41 0)
			(effects
				(font
					(size 1.27 1.27)
					(thickness 0.15)
				)
				(justify left bottom)
				(hide yes)
			)
		)
		(property "Author" "Antmicro"
			(at 223.52 232.41 0)
			(effects
				(font
					(size 1.27 1.27)
					(thickness 0.15)
				)
				(justify left bottom)
				(hide yes)
			)
		)
		(property "Val" "100n"
			(at 251.46 215.9063 90)
			(effects
				(font
					(size 1.27 1.27)
					(thickness 0.15)
				)
				(justify left)
			)
		)
		(property "Voltage" "50V"
			(at 220.98 232.41 0)
			(effects
				(font
					(size 1.27 1.27)
				)
				(justify left bottom)
				(hide yes)
			)
		)
		(property "Dielectric" "X5R"
			(at 218.44 232.41 0)
			(effects
				(font
					(size 1.27 1.27)
				)
				(justify left bottom)
				(hide yes)
			)
		)
		(pin "1"
		)
		(pin "2"
		)
		(instances
			(project "cm4-baseboard"
				(path ""
					(reference "C828")
					(unit 1)
				)
			)
		)
	)
	(symbol
		(lib_id "antmicropower:GND")
		(at 248.92 217.17 0)
		(unit 1)
		(exclude_from_sim no)
		(in_bom yes)
		(on_board yes)
		(dnp no)
		(property "Reference" "#PWR040"
			(at 257.81 219.71 0)
			(effects
				(font
					(size 1.27 1.27)
					(thickness 0.15)
				)
				(justify left bottom)
				(hide yes)
			)
		)
		(property "Value" "GND"
			(at 245.364 219.202 0)
			(effects
				(font
					(size 1.27 1.27)
				)
			)
		)
		(property "Footprint" ""
			(at 257.81 224.79 0)
			(effects
				(font
					(size 1.27 1.27)
					(thickness 0.15)
				)
				(justify left bottom)
				(hide yes)
			)
		)
		(property "Datasheet" ""
			(at 257.81 229.87 0)
			(effects
				(font
					(size 1.27 1.27)
					(thickness 0.15)
				)
				(justify left bottom)
				(hide yes)
			)
		)
		(property "Description" ""
			(at 248.92 217.17 0)
			(effects
				(font
					(size 1.27 1.27)
				)
				(hide yes)
			)
		)
		(property "Author" "Antmicro"
			(at 257.81 224.79 0)
			(effects
				(font
					(size 1.27 1.27)
					(thickness 0.15)
				)
				(justify left bottom)
				(hide yes)
			)
		)
		(property "License" "Apache-2.0"
			(at 257.81 227.33 0)
			(effects
				(font
					(size 1.27 1.27)
					(thickness 0.15)
				)
				(justify left bottom)
				(hide yes)
			)
		)
		(pin "1"
		)
		(instances
			(project "cm4-baseboard"
				(path ""
					(reference "#PWR040")
					(unit 1)
				)
			)
		)
	)
	(symbol
		(lib_id "antmicroCapacitors0402:C_10p_0402")
		(at 320.04 165.1 90)
		(unit 1)
		(exclude_from_sim no)
		(in_bom yes)
		(on_board yes)
		(dnp no)
		(fields_autoplaced yes)
		(property "Reference" "C815"
			(at 322.58 161.2835 90)
			(effects
				(font
					(size 1.27 1.27)
					(thickness 0.15)
				)
				(justify right)
			)
		)
		(property "Value" "C_10p_0402"
			(at 330.2 144.78 0)
			(effects
				(font
					(size 1.27 1.27)
					(thickness 0.15)
				)
				(justify left bottom)
				(hide yes)
			)
		)
		(property "Footprint" "antmicro-footprints:C_0402_1005Metric"
			(at 332.74 144.78 0)
			(effects
				(font
					(size 1.27 1.27)
					(thickness 0.15)
				)
				(justify left bottom)
				(hide yes)
			)
		)
		(property "Datasheet" "https://www.murata.com/products/productdetail?partno=GCM1555C1H100GA16%23"
			(at 335.28 144.78 0)
			(effects
				(font
					(size 1.27 1.27)
					(thickness 0.15)
				)
				(justify left bottom)
				(hide yes)
			)
		)
		(property "Description" ""
			(at 320.04 165.1 0)
			(effects
				(font
					(size 1.27 1.27)
				)
				(hide yes)
			)
		)
		(property "MPN" "GCM1555C1H100GA16D"
			(at 337.82 144.78 0)
			(effects
				(font
					(size 1.27 1.27)
					(thickness 0.15)
				)
				(justify left bottom)
				(hide yes)
			)
		)
		(property "Manufacturer" "Murata"
			(at 340.36 144.78 0)
			(effects
				(font
					(size 1.27 1.27)
					(thickness 0.15)
				)
				(justify left bottom)
				(hide yes)
			)
		)
		(property "License" "Apache-2.0"
			(at 342.9 144.78 0)
			(effects
				(font
					(size 1.27 1.27)
					(thickness 0.15)
				)
				(justify left bottom)
				(hide yes)
			)
		)
		(property "Author" "Antmicro"
			(at 345.44 144.78 0)
			(effects
				(font
					(size 1.27 1.27)
					(thickness 0.15)
				)
				(justify left bottom)
				(hide yes)
			)
		)
		(property "Val" "10p"
			(at 322.58 163.8235 90)
			(effects
				(font
					(size 1.27 1.27)
					(thickness 0.15)
				)
				(justify right)
			)
		)
		(property "Voltage" "50V"
			(at 347.98 144.78 0)
			(effects
				(font
					(size 1.27 1.27)
				)
				(justify left bottom)
				(hide yes)
			)
		)
		(property "Dielectric" "C0G"
			(at 350.52 144.78 0)
			(effects
				(font
					(size 1.27 1.27)
				)
				(justify left bottom)
				(hide yes)
			)
		)
		(pin "1"
		)
		(pin "2"
		)
		(instances
			(project "cm4-baseboard"
				(path ""
					(reference "C815")
					(unit 1)
				)
			)
		)
	)
	(symbol
		(lib_id "antmicroCapacitors0402:C_4u7_0402")
		(at 257.81 74.93 90)
		(unit 1)
		(exclude_from_sim no)
		(in_bom yes)
		(on_board yes)
		(dnp no)
		(fields_autoplaced yes)
		(property "Reference" "C803"
			(at 260.35 71.1135 90)
			(effects
				(font
					(size 1.27 1.27)
					(thickness 0.15)
				)
				(justify right)
			)
		)
		(property "Value" "C_4u7_0402"
			(at 267.97 54.61 0)
			(effects
				(font
					(size 1.27 1.27)
					(thickness 0.15)
				)
				(justify left bottom)
				(hide yes)
			)
		)
		(property "Footprint" "antmicro-footprints:C_0402_1005Metric"
			(at 270.51 54.61 0)
			(effects
				(font
					(size 1.27 1.27)
					(thickness 0.15)
				)
				(justify left bottom)
				(hide yes)
			)
		)
		(property "Datasheet" "https://www.murata.com/products/productdetail?partno=GRM155R61A475MEAA%23"
			(at 273.05 54.61 0)
			(effects
				(font
					(size 1.27 1.27)
					(thickness 0.15)
				)
				(justify left bottom)
				(hide yes)
			)
		)
		(property "Description" ""
			(at 257.81 74.93 0)
			(effects
				(font
					(size 1.27 1.27)
				)
				(hide yes)
			)
		)
		(property "MPN" "GRM155R61A475MEAAD"
			(at 275.59 54.61 0)
			(effects
				(font
					(size 1.27 1.27)
					(thickness 0.15)
				)
				(justify left bottom)
				(hide yes)
			)
		)
		(property "Manufacturer" "Murata"
			(at 278.13 54.61 0)
			(effects
				(font
					(size 1.27 1.27)
					(thickness 0.15)
				)
				(justify left bottom)
				(hide yes)
			)
		)
		(property "License" "Apache-2.0"
			(at 280.67 54.61 0)
			(effects
				(font
					(size 1.27 1.27)
					(thickness 0.15)
				)
				(justify left bottom)
				(hide yes)
			)
		)
		(property "Author" "Antmicro"
			(at 283.21 54.61 0)
			(effects
				(font
					(size 1.27 1.27)
					(thickness 0.15)
				)
				(justify left bottom)
				(hide yes)
			)
		)
		(property "Val" "4u7"
			(at 260.35 73.6535 90)
			(effects
				(font
					(size 1.27 1.27)
					(thickness 0.15)
				)
				(justify right)
			)
		)
		(property "Voltage" ""
			(at 285.75 54.61 0)
			(effects
				(font
					(size 1.27 1.27)
				)
				(justify left bottom)
				(hide yes)
			)
		)
		(property "Dielectric" ""
			(at 288.29 54.61 0)
			(effects
				(font
					(size 1.27 1.27)
				)
				(justify left bottom)
				(hide yes)
			)
		)
		(pin "1"
		)
		(pin "2"
		)
		(instances
			(project "cm4-baseboard"
				(path ""
					(reference "C803")
					(unit 1)
				)
			)
		)
	)
	(symbol
		(lib_id "antmicropower:GND")
		(at 256.54 232.41 0)
		(unit 1)
		(exclude_from_sim no)
		(in_bom yes)
		(on_board yes)
		(dnp no)
		(property "Reference" "#PWR041"
			(at 265.43 234.95 0)
			(effects
				(font
					(size 1.27 1.27)
					(thickness 0.15)
				)
				(justify left bottom)
				(hide yes)
			)
		)
		(property "Value" "GND"
			(at 256.54 236.22 0)
			(effects
				(font
					(size 1.27 1.27)
				)
			)
		)
		(property "Footprint" ""
			(at 265.43 240.03 0)
			(effects
				(font
					(size 1.27 1.27)
					(thickness 0.15)
				)
				(justify left bottom)
				(hide yes)
			)
		)
		(property "Datasheet" ""
			(at 265.43 245.11 0)
			(effects
				(font
					(size 1.27 1.27)
					(thickness 0.15)
				)
				(justify left bottom)
				(hide yes)
			)
		)
		(property "Description" ""
			(at 256.54 232.41 0)
			(effects
				(font
					(size 1.27 1.27)
				)
				(hide yes)
			)
		)
		(property "Author" "Antmicro"
			(at 265.43 240.03 0)
			(effects
				(font
					(size 1.27 1.27)
					(thickness 0.15)
				)
				(justify left bottom)
				(hide yes)
			)
		)
		(property "License" "Apache-2.0"
			(at 265.43 242.57 0)
			(effects
				(font
					(size 1.27 1.27)
					(thickness 0.15)
				)
				(justify left bottom)
				(hide yes)
			)
		)
		(pin "1"
		)
		(instances
			(project "cm4-baseboard"
				(path ""
					(reference "#PWR041")
					(unit 1)
				)
			)
		)
	)
	(symbol
		(lib_id "antmicroCapacitors0402:C_2u2_0402")
		(at 273.05 132.08 180)
		(unit 1)
		(exclude_from_sim no)
		(in_bom yes)
		(on_board yes)
		(dnp no)
		(property "Reference" "C805"
			(at 266.7 130.81 0)
			(effects
				(font
					(size 1.27 1.27)
					(thickness 0.15)
				)
			)
		)
		(property "Value" "C_2u2_0402"
			(at 252.73 121.92 0)
			(effects
				(font
					(size 1.27 1.27)
					(thickness 0.15)
				)
				(justify left bottom)
				(hide yes)
			)
		)
		(property "Footprint" "antmicro-footprints:C_0402_1005Metric"
			(at 252.73 119.38 0)
			(effects
				(font
					(size 1.27 1.27)
					(thickness 0.15)
				)
				(justify left bottom)
				(hide yes)
			)
		)
		(property "Datasheet" "https://product.tdk.com/en/search/capacitor/ceramic/mlcc/info?part_no=C1005X5R1A225K050BC"
			(at 252.73 116.84 0)
			(effects
				(font
					(size 1.27 1.27)
					(thickness 0.15)
				)
				(justify left bottom)
				(hide yes)
			)
		)
		(property "Description" ""
			(at 273.05 132.08 0)
			(effects
				(font
					(size 1.27 1.27)
				)
				(hide yes)
			)
		)
		(property "MPN" "C1005X5R1A225K050BC"
			(at 252.73 114.3 0)
			(effects
				(font
					(size 1.27 1.27)
					(thickness 0.15)
				)
				(justify left bottom)
				(hide yes)
			)
		)
		(property "Manufacturer" "TDK"
			(at 252.73 111.76 0)
			(effects
				(font
					(size 1.27 1.27)
					(thickness 0.15)
				)
				(justify left bottom)
				(hide yes)
			)
		)
		(property "License" "Apache-2.0"
			(at 252.73 109.22 0)
			(effects
				(font
					(size 1.27 1.27)
					(thickness 0.15)
				)
				(justify left bottom)
				(hide yes)
			)
		)
		(property "Author" "Antmicro"
			(at 252.73 106.68 0)
			(effects
				(font
					(size 1.27 1.27)
					(thickness 0.15)
				)
				(justify left bottom)
				(hide yes)
			)
		)
		(property "Val" "2u2"
			(at 273.05 130.81 0)
			(effects
				(font
					(size 1.27 1.27)
					(thickness 0.15)
				)
			)
		)
		(property "Voltage" ""
			(at 252.73 104.14 0)
			(effects
				(font
					(size 1.27 1.27)
				)
				(justify left bottom)
				(hide yes)
			)
		)
		(property "Dielectric" ""
			(at 252.73 101.6 0)
			(effects
				(font
					(size 1.27 1.27)
				)
				(justify left bottom)
				(hide yes)
			)
		)
		(pin "1"
		)
		(pin "2"
		)
		(instances
			(project "cm4-baseboard"
				(path ""
					(reference "C805")
					(unit 1)
				)
			)
		)
	)
	(symbol
		(lib_id "antmicroTVSDiodes:PUSB3F96X_PASS")
		(at 149.86 101.6 0)
		(mirror y)
		(unit 1)
		(exclude_from_sim no)
		(in_bom yes)
		(on_board yes)
		(dnp no)
		(fields_autoplaced yes)
		(property "Reference" "D806"
			(at 142.24 93.98 0)
			(effects
				(font
					(size 1.27 1.27)
					(thickness 0.15)
				)
			)
		)
		(property "Value" "PUSB3F96X_PASS"
			(at 124.46 109.22 0)
			(effects
				(font
					(size 1.27 1.27)
					(thickness 0.15)
				)
				(justify left bottom)
				(hide yes)
			)
		)
		(property "Footprint" "antmicro-footprints:Nexperia_DFN-10_2.5x1mm_P0.5mm"
			(at 124.46 111.76 0)
			(effects
				(font
					(size 1.27 1.27)
					(thickness 0.15)
				)
				(justify left bottom)
				(hide yes)
			)
		)
		(property "Datasheet" "https://mouser.com/datasheet/2/916/PUSB3F96-1600324.pdf"
			(at 124.46 114.3 0)
			(effects
				(font
					(size 1.27 1.27)
					(thickness 0.15)
				)
				(justify left bottom)
				(hide yes)
			)
		)
		(property "Description" ""
			(at 149.86 101.6 0)
			(effects
				(font
					(size 1.27 1.27)
				)
				(hide yes)
			)
		)
		(property "Manufacturer" "Nexperia"
			(at 124.46 116.84 0)
			(effects
				(font
					(size 1.27 1.27)
					(thickness 0.15)
				)
				(justify left bottom)
				(hide yes)
			)
		)
		(property "MPN" "PUSB3F96X"
			(at 142.24 96.52 0)
			(effects
				(font
					(size 1.27 1.27)
					(thickness 0.15)
				)
			)
		)
		(property "Author" "Antmicro"
			(at 124.46 119.38 0)
			(effects
				(font
					(size 1.27 1.27)
					(thickness 0.15)
				)
				(justify left bottom)
				(hide yes)
			)
		)
		(property "License" "Apache-2.0"
			(at 124.46 121.92 0)
			(effects
				(font
					(size 1.27 1.27)
					(thickness 0.15)
				)
				(justify left bottom)
				(hide yes)
			)
		)
		(pin "1"
		)
		(pin "10"
		)
		(pin "2"
		)
		(pin "3"
		)
		(pin "4"
		)
		(pin "5"
		)
		(pin "6"
		)
		(pin "7"
		)
		(pin "8"
		)
		(pin "9"
		)
		(instances
			(project "cm4-baseboard"
				(path ""
					(reference "D806")
					(unit 1)
				)
			)
		)
	)
	(symbol
		(lib_id "antmicropower:+3V3")
		(at 151.13 35.56 0)
		(unit 1)
		(exclude_from_sim no)
		(in_bom yes)
		(on_board yes)
		(dnp no)
		(property "Reference" "#PWR0815"
			(at 166.37 38.1 0)
			(effects
				(font
					(size 1.27 1.27)
					(thickness 0.15)
				)
				(justify left bottom)
				(hide yes)
			)
		)
		(property "Value" "+3V3"
			(at 151.13 30.48 0)
			(effects
				(font
					(size 1.27 1.27)
					(thickness 0.15)
				)
			)
		)
		(property "Footprint" ""
			(at 166.37 43.18 0)
			(effects
				(font
					(size 1.27 1.27)
					(thickness 0.15)
				)
				(justify left bottom)
				(hide yes)
			)
		)
		(property "Datasheet" ""
			(at 166.37 45.72 0)
			(effects
				(font
					(size 1.27 1.27)
					(thickness 0.15)
				)
				(justify left bottom)
				(hide yes)
			)
		)
		(property "Description" ""
			(at 151.13 35.56 0)
			(effects
				(font
					(size 1.27 1.27)
				)
				(hide yes)
			)
		)
		(property "Author" "Antmicro"
			(at 166.37 43.18 0)
			(effects
				(font
					(size 1.27 1.27)
					(thickness 0.15)
				)
				(justify left bottom)
				(hide yes)
			)
		)
		(property "License" "Apache-2.0"
			(at 166.37 45.72 0)
			(effects
				(font
					(size 1.27 1.27)
					(thickness 0.15)
				)
				(justify left bottom)
				(hide yes)
			)
		)
		(pin "1"
		)
		(instances
			(project "cm4-baseboard"
				(path ""
					(reference "#PWR0815")
					(unit 1)
				)
			)
		)
	)
	(symbol
		(lib_id "antmicroCapacitors0402:C_39p_0402")
		(at 350.52 114.3 90)
		(unit 1)
		(exclude_from_sim no)
		(in_bom yes)
		(on_board yes)
		(dnp no)
		(property "Reference" "C824"
			(at 352.298 110.49 90)
			(effects
				(font
					(size 1.27 1.27)
					(thickness 0.15)
				)
				(justify right)
			)
		)
		(property "Value" "C_39p_0402"
			(at 360.68 93.98 0)
			(effects
				(font
					(size 1.27 1.27)
					(thickness 0.15)
				)
				(justify left bottom)
				(hide yes)
			)
		)
		(property "Footprint" "antmicro-footprints:C_0402_1005Metric"
			(at 363.22 93.98 0)
			(effects
				(font
					(size 1.27 1.27)
					(thickness 0.15)
				)
				(justify left bottom)
				(hide yes)
			)
		)
		(property "Datasheet" "https://spicat.kyocera-avx.com/product/mlcc/chartview/04025A390JAT2A/"
			(at 365.76 93.98 0)
			(effects
				(font
					(size 1.27 1.27)
					(thickness 0.15)
				)
				(justify left bottom)
				(hide yes)
			)
		)
		(property "Description" "SMD Multilayer Ceramic Capacitor, 39 pF, 50 V, 0402 [1005 Metric], ± 5%, C0G / NP0, AVX 0402 MLCC"
			(at 383.54 93.98 0)
			(effects
				(font
					(size 1.27 1.27)
				)
				(justify left bottom)
				(hide yes)
			)
		)
		(property "MPN" "04025A390JAT2A"
			(at 368.3 93.98 0)
			(effects
				(font
					(size 1.27 1.27)
					(thickness 0.15)
				)
				(justify left bottom)
				(hide yes)
			)
		)
		(property "Manufacturer" "KYOCERA AVX"
			(at 370.84 93.98 0)
			(effects
				(font
					(size 1.27 1.27)
					(thickness 0.15)
				)
				(justify left bottom)
				(hide yes)
			)
		)
		(property "License" "Apache-2.0"
			(at 373.38 93.98 0)
			(effects
				(font
					(size 1.27 1.27)
					(thickness 0.15)
				)
				(justify left bottom)
				(hide yes)
			)
		)
		(property "Author" "Antmicro"
			(at 375.92 93.98 0)
			(effects
				(font
					(size 1.27 1.27)
					(thickness 0.15)
				)
				(justify left bottom)
				(hide yes)
			)
		)
		(property "Val" "39p"
			(at 352.298 113.03 90)
			(effects
				(font
					(size 1.27 1.27)
					(thickness 0.15)
				)
				(justify right)
			)
		)
		(property "Voltage" ""
			(at 378.46 93.98 0)
			(effects
				(font
					(size 1.27 1.27)
				)
				(justify left bottom)
				(hide yes)
			)
		)
		(property "Dielectric" ""
			(at 381 93.98 0)
			(effects
				(font
					(size 1.27 1.27)
				)
				(justify left bottom)
				(hide yes)
			)
		)
		(pin "2"
		)
		(pin "1"
		)
		(instances
			(project ""
				(path ""
					(reference "C824")
					(unit 1)
				)
			)
		)
	)
	(symbol
		(lib_id "antmicroTVSDiodes:PUSB3F96X_PASS")
		(at 148.59 39.37 0)
		(mirror y)
		(unit 1)
		(exclude_from_sim no)
		(in_bom yes)
		(on_board yes)
		(dnp no)
		(fields_autoplaced yes)
		(property "Reference" "D805"
			(at 140.97 31.75 0)
			(effects
				(font
					(size 1.27 1.27)
					(thickness 0.15)
				)
			)
		)
		(property "Value" "PUSB3F96X_PASS"
			(at 123.19 46.99 0)
			(effects
				(font
					(size 1.27 1.27)
					(thickness 0.15)
				)
				(justify left bottom)
				(hide yes)
			)
		)
		(property "Footprint" "antmicro-footprints:Nexperia_DFN-10_2.5x1mm_P0.5mm"
			(at 123.19 49.53 0)
			(effects
				(font
					(size 1.27 1.27)
					(thickness 0.15)
				)
				(justify left bottom)
				(hide yes)
			)
		)
		(property "Datasheet" "https://mouser.com/datasheet/2/916/PUSB3F96-1600324.pdf"
			(at 123.19 52.07 0)
			(effects
				(font
					(size 1.27 1.27)
					(thickness 0.15)
				)
				(justify left bottom)
				(hide yes)
			)
		)
		(property "Description" ""
			(at 148.59 39.37 0)
			(effects
				(font
					(size 1.27 1.27)
				)
				(hide yes)
			)
		)
		(property "Manufacturer" "Nexperia"
			(at 123.19 54.61 0)
			(effects
				(font
					(size 1.27 1.27)
					(thickness 0.15)
				)
				(justify left bottom)
				(hide yes)
			)
		)
		(property "MPN" "PUSB3F96X"
			(at 140.97 34.29 0)
			(effects
				(font
					(size 1.27 1.27)
					(thickness 0.15)
				)
			)
		)
		(property "Author" "Antmicro"
			(at 123.19 57.15 0)
			(effects
				(font
					(size 1.27 1.27)
					(thickness 0.15)
				)
				(justify left bottom)
				(hide yes)
			)
		)
		(property "License" "Apache-2.0"
			(at 123.19 59.69 0)
			(effects
				(font
					(size 1.27 1.27)
					(thickness 0.15)
				)
				(justify left bottom)
				(hide yes)
			)
		)
		(pin "1"
		)
		(pin "10"
		)
		(pin "2"
		)
		(pin "3"
		)
		(pin "4"
		)
		(pin "5"
		)
		(pin "6"
		)
		(pin "7"
		)
		(pin "8"
		)
		(pin "9"
		)
		(instances
			(project "cm4-baseboard"
				(path ""
					(reference "D805")
					(unit 1)
				)
			)
		)
	)
	(symbol
		(lib_id "antmicroCapacitors0402:C_2u2_0402")
		(at 273.05 137.16 180)
		(unit 1)
		(exclude_from_sim no)
		(in_bom yes)
		(on_board yes)
		(dnp no)
		(property "Reference" "C806"
			(at 266.7 135.89 0)
			(effects
				(font
					(size 1.27 1.27)
					(thickness 0.15)
				)
			)
		)
		(property "Value" "C_2u2_0402"
			(at 252.73 127 0)
			(effects
				(font
					(size 1.27 1.27)
					(thickness 0.15)
				)
				(justify left bottom)
				(hide yes)
			)
		)
		(property "Footprint" "antmicro-footprints:C_0402_1005Metric"
			(at 252.73 124.46 0)
			(effects
				(font
					(size 1.27 1.27)
					(thickness 0.15)
				)
				(justify left bottom)
				(hide yes)
			)
		)
		(property "Datasheet" "https://product.tdk.com/en/search/capacitor/ceramic/mlcc/info?part_no=C1005X5R1A225K050BC"
			(at 252.73 121.92 0)
			(effects
				(font
					(size 1.27 1.27)
					(thickness 0.15)
				)
				(justify left bottom)
				(hide yes)
			)
		)
		(property "Description" ""
			(at 273.05 137.16 0)
			(effects
				(font
					(size 1.27 1.27)
				)
				(hide yes)
			)
		)
		(property "MPN" "C1005X5R1A225K050BC"
			(at 252.73 119.38 0)
			(effects
				(font
					(size 1.27 1.27)
					(thickness 0.15)
				)
				(justify left bottom)
				(hide yes)
			)
		)
		(property "Manufacturer" "TDK"
			(at 252.73 116.84 0)
			(effects
				(font
					(size 1.27 1.27)
					(thickness 0.15)
				)
				(justify left bottom)
				(hide yes)
			)
		)
		(property "License" "Apache-2.0"
			(at 252.73 114.3 0)
			(effects
				(font
					(size 1.27 1.27)
					(thickness 0.15)
				)
				(justify left bottom)
				(hide yes)
			)
		)
		(property "Author" "Antmicro"
			(at 252.73 111.76 0)
			(effects
				(font
					(size 1.27 1.27)
					(thickness 0.15)
				)
				(justify left bottom)
				(hide yes)
			)
		)
		(property "Val" "2u2"
			(at 273.05 135.89 0)
			(effects
				(font
					(size 1.27 1.27)
					(thickness 0.15)
				)
			)
		)
		(property "Voltage" ""
			(at 252.73 109.22 0)
			(effects
				(font
					(size 1.27 1.27)
				)
				(justify left bottom)
				(hide yes)
			)
		)
		(property "Dielectric" ""
			(at 252.73 106.68 0)
			(effects
				(font
					(size 1.27 1.27)
				)
				(justify left bottom)
				(hide yes)
			)
		)
		(pin "1"
		)
		(pin "2"
		)
		(instances
			(project "cm4-baseboard"
				(path ""
					(reference "C806")
					(unit 1)
				)
			)
		)
	)
	(symbol
		(lib_id "antmicroCapacitors0402:C_template_name_0402")
		(at 322.58 114.3 270)
		(mirror x)
		(unit 1)
		(exclude_from_sim no)
		(in_bom no)
		(on_board yes)
		(dnp yes)
		(property "Reference" "C816"
			(at 323.85 110.4836 90)
			(effects
				(font
					(size 1.27 1.27)
					(thickness 0.15)
				)
				(justify left)
			)
		)
		(property "Value" "C_template_name_0402"
			(at 312.42 93.98 0)
			(effects
				(font
					(size 1.27 1.27)
					(thickness 0.15)
				)
				(justify left bottom)
				(hide yes)
			)
		)
		(property "Footprint" "antmicro-footprints:C_0402_1005Metric"
			(at 309.88 93.98 0)
			(effects
				(font
					(size 1.27 1.27)
					(thickness 0.15)
				)
				(justify left bottom)
				(hide yes)
			)
		)
		(property "Datasheet" "template_datasheet"
			(at 307.34 93.98 0)
			(effects
				(font
					(size 1.27 1.27)
					(thickness 0.15)
				)
				(justify left bottom)
				(hide yes)
			)
		)
		(property "Description" ""
			(at 322.58 114.3 0)
			(effects
				(font
					(size 1.27 1.27)
				)
				(hide yes)
			)
		)
		(property "MPN" "template_MPN"
			(at 304.8 93.98 0)
			(effects
				(font
					(size 1.27 1.27)
					(thickness 0.15)
				)
				(justify left bottom)
				(hide yes)
			)
		)
		(property "Manufacturer" "template_manufacturer"
			(at 302.26 93.98 0)
			(effects
				(font
					(size 1.27 1.27)
					(thickness 0.15)
				)
				(justify left bottom)
				(hide yes)
			)
		)
		(property "License" "Apache-2.0"
			(at 299.72 93.98 0)
			(effects
				(font
					(size 1.27 1.27)
					(thickness 0.15)
				)
				(justify left bottom)
				(hide yes)
			)
		)
		(property "Author" "Antmicro"
			(at 297.18 93.98 0)
			(effects
				(font
					(size 1.27 1.27)
					(thickness 0.15)
				)
				(justify left bottom)
				(hide yes)
			)
		)
		(property "Val" "template_value"
			(at 326.39 111.7537 0)
			(effects
				(font
					(size 1.27 1.27)
					(thickness 0.15)
				)
				(hide yes)
			)
		)
		(property "Voltage" "template_voltage"
			(at 294.64 93.98 0)
			(effects
				(font
					(size 1.27 1.27)
				)
				(justify left bottom)
				(hide yes)
			)
		)
		(property "Dielectric" "template_dielectric"
			(at 292.1 93.98 0)
			(effects
				(font
					(size 1.27 1.27)
				)
				(justify left bottom)
				(hide yes)
			)
		)
		(pin "1"
		)
		(pin "2"
		)
		(instances
			(project "cm4-baseboard"
				(path ""
					(reference "C816")
					(unit 1)
				)
			)
		)
	)
)
